FILE_TYPE = MACRO_DRAWING;
SET COLOR_WIRE YELLOW;
SET COLOR_PROP MONO;
SET COLOR_DOT WHITE;
SET COLOR_ARC YELLOW;
SET COLOR_BODY GREEN;
SET COLOR_NOTE MONO;
SET PROP_DISPLAY VALUE;
SET PAGE_NUMBER P33;
FORCEADD OFFPAGE..1
(-6450 2600);
FORCEPROP 2 LAST $XR0 67 
J 0
(-6701 2600);
DISPLAY 0.638298 (-6701 2600);
PAINT MONO (-6701 2600);
FORCEPROP 2 LAST CDS_LIB mstr_standard
J 0
(-6450 2600);
PAINT MONO (-6450 2600);
DISPLAY INVISIBLE (-6450 2600);
FORCEPROP 1 LAST OFFPAGE TRUE
J 0
(-6125 2475);
DISPLAY 1.170213 (-6125 2475);
PAINT GREEN (-6125 2475);
DISPLAY INVISIBLE (-6125 2475);
FORCEPROP 1 LAST COMMENT_BODY TRUE
J 0
(-6325 2500);
DISPLAY 1.170213 (-6325 2500);
PAINT GREEN (-6325 2500);
DISPLAY INVISIBLE (-6325 2500);
FORCEPROP 2 LAST PATH I1
J 0
(-6400 2675);
DISPLAY 1.021277 (-6400 2675);
PAINT ORANGE (-6400 2675);
DISPLAY INVISIBLE (-6400 2675);
FORCEADD TAP..1
R 2
(-5250 1900);
FORCEPROP 3 LASTPIN (-5200 1900) SIG_NAME UPI_CPU1_CPU0_P0P0_DN<13>
J 0
(-5190 1910);
DISPLAY 0.659574 (-5190 1910);
PAINT MONO (-5190 1910);
DISPLAY INVISIBLE (-5190 1910);
FORCEPROP 1 LASTPIN (-5200 1900) BN 13
J 2
(-5188 1908);
DISPLAY 0.617021 (-5188 1908);
PAINT PINK (-5188 1908);
FORCEPROP 2 LAST CDS_LIB mstr_standard
J 0
(-5250 1900);
PAINT MONO (-5250 1900);
DISPLAY INVISIBLE (-5250 1900);
FORCEPROP 1 LAST BODY_TYPE PLUMBING
J 2
(-5250 1950);
DISPLAY 1.446809 (-5250 1950);
PAINT GREEN (-5250 1950);
DISPLAY INVISIBLE (-5250 1950);
FORCEPROP 1 LAST HDL_TAP TRUE
J 2
(-5575 1775);
DISPLAY 1.446809 (-5575 1775);
PAINT GREEN (-5575 1775);
DISPLAY INVISIBLE (-5575 1775);
FORCEPROP 1 LAST PATH I10
J 2
(-5248 1900);
DISPLAY 0.872340 (-5248 1900);
PAINT GREEN (-5248 1900);
DISPLAY INVISIBLE (-5248 1900);
FORCEADD TAP..1
R 2
(-5250 2000);
FORCEPROP 3 LASTPIN (-5200 2000) SIG_NAME UPI_CPU1_CPU0_P0P0_DN<11>
J 0
(-5190 2010);
DISPLAY 0.659574 (-5190 2010);
PAINT MONO (-5190 2010);
DISPLAY INVISIBLE (-5190 2010);
FORCEPROP 1 LASTPIN (-5200 2000) BN 11
J 2
(-5188 2008);
DISPLAY 0.617021 (-5188 2008);
PAINT PINK (-5188 2008);
FORCEPROP 2 LAST CDS_LIB mstr_standard
J 0
(-5250 2000);
PAINT MONO (-5250 2000);
DISPLAY INVISIBLE (-5250 2000);
FORCEPROP 1 LAST BODY_TYPE PLUMBING
J 2
(-5250 2050);
DISPLAY 1.446809 (-5250 2050);
PAINT GREEN (-5250 2050);
DISPLAY INVISIBLE (-5250 2050);
FORCEPROP 1 LAST HDL_TAP TRUE
J 2
(-5575 1875);
DISPLAY 1.446809 (-5575 1875);
PAINT GREEN (-5575 1875);
DISPLAY INVISIBLE (-5575 1875);
FORCEPROP 1 LAST PATH I11
J 2
(-5248 2000);
DISPLAY 0.872340 (-5248 2000);
PAINT GREEN (-5248 2000);
DISPLAY INVISIBLE (-5248 2000);
FORCEADD TAP..1
R 2
(-5250 2100);
FORCEPROP 3 LASTPIN (-5200 2100) SIG_NAME UPI_CPU1_CPU0_P0P0_DN<9>
J 0
(-5190 2110);
DISPLAY 0.659574 (-5190 2110);
PAINT MONO (-5190 2110);
DISPLAY INVISIBLE (-5190 2110);
FORCEPROP 1 LASTPIN (-5200 2100) BN 9
J 2
(-5188 2108);
DISPLAY 0.617021 (-5188 2108);
PAINT PINK (-5188 2108);
FORCEPROP 2 LAST CDS_LIB mstr_standard
J 0
(-5250 2100);
PAINT MONO (-5250 2100);
DISPLAY INVISIBLE (-5250 2100);
FORCEPROP 1 LAST BODY_TYPE PLUMBING
J 2
(-5250 2150);
DISPLAY 1.446809 (-5250 2150);
PAINT GREEN (-5250 2150);
DISPLAY INVISIBLE (-5250 2150);
FORCEPROP 1 LAST HDL_TAP TRUE
J 2
(-5575 1975);
DISPLAY 1.446809 (-5575 1975);
PAINT GREEN (-5575 1975);
DISPLAY INVISIBLE (-5575 1975);
FORCEPROP 1 LAST PATH I13
J 2
(-5248 2100);
DISPLAY 0.872340 (-5248 2100);
PAINT GREEN (-5248 2100);
DISPLAY INVISIBLE (-5248 2100);
FORCEADD TAP..1
R 2
(-5250 2050);
FORCEPROP 3 LASTPIN (-5200 2050) SIG_NAME UPI_CPU1_CPU0_P0P0_DN<10>
J 0
(-5190 2060);
DISPLAY 0.659574 (-5190 2060);
PAINT MONO (-5190 2060);
DISPLAY INVISIBLE (-5190 2060);
FORCEPROP 1 LASTPIN (-5200 2050) BN 10
J 2
(-5188 2058);
DISPLAY 0.617021 (-5188 2058);
PAINT PINK (-5188 2058);
FORCEPROP 2 LAST CDS_LIB mstr_standard
J 0
(-5250 2050);
PAINT MONO (-5250 2050);
DISPLAY INVISIBLE (-5250 2050);
FORCEPROP 1 LAST BODY_TYPE PLUMBING
J 2
(-5250 2100);
DISPLAY 1.446809 (-5250 2100);
PAINT GREEN (-5250 2100);
DISPLAY INVISIBLE (-5250 2100);
FORCEPROP 1 LAST HDL_TAP TRUE
J 2
(-5575 1925);
DISPLAY 1.446809 (-5575 1925);
PAINT GREEN (-5575 1925);
DISPLAY INVISIBLE (-5575 1925);
FORCEPROP 1 LAST PATH I14
J 2
(-5248 2050);
DISPLAY 0.872340 (-5248 2050);
PAINT GREEN (-5248 2050);
DISPLAY INVISIBLE (-5248 2050);
FORCEADD TAP..1
R 2
(-5250 2250);
FORCEPROP 3 LASTPIN (-5200 2250) SIG_NAME UPI_CPU1_CPU0_P0P0_DN<6>
J 0
(-5190 2260);
DISPLAY 0.659574 (-5190 2260);
PAINT MONO (-5190 2260);
DISPLAY INVISIBLE (-5190 2260);
FORCEPROP 1 LASTPIN (-5200 2250) BN 6
J 2
(-5188 2258);
DISPLAY 0.617021 (-5188 2258);
PAINT PINK (-5188 2258);
FORCEPROP 2 LAST CDS_LIB mstr_standard
J 0
(-5250 2250);
PAINT MONO (-5250 2250);
DISPLAY INVISIBLE (-5250 2250);
FORCEPROP 1 LAST BODY_TYPE PLUMBING
J 2
(-5250 2300);
DISPLAY 1.446809 (-5250 2300);
PAINT GREEN (-5250 2300);
DISPLAY INVISIBLE (-5250 2300);
FORCEPROP 1 LAST HDL_TAP TRUE
J 2
(-5575 2125);
DISPLAY 1.446809 (-5575 2125);
PAINT GREEN (-5575 2125);
DISPLAY INVISIBLE (-5575 2125);
FORCEPROP 1 LAST PATH I15
J 2
(-5248 2250);
DISPLAY 0.872340 (-5248 2250);
PAINT GREEN (-5248 2250);
DISPLAY INVISIBLE (-5248 2250);
FORCEADD TAP..1
R 2
(-5250 2200);
FORCEPROP 3 LASTPIN (-5200 2200) SIG_NAME UPI_CPU1_CPU0_P0P0_DN<7>
J 0
(-5190 2210);
DISPLAY 0.659574 (-5190 2210);
PAINT MONO (-5190 2210);
DISPLAY INVISIBLE (-5190 2210);
FORCEPROP 1 LASTPIN (-5200 2200) BN 7
J 2
(-5188 2208);
DISPLAY 0.617021 (-5188 2208);
PAINT PINK (-5188 2208);
FORCEPROP 2 LAST CDS_LIB mstr_standard
J 0
(-5250 2200);
PAINT MONO (-5250 2200);
DISPLAY INVISIBLE (-5250 2200);
FORCEPROP 1 LAST BODY_TYPE PLUMBING
J 2
(-5250 2250);
DISPLAY 1.446809 (-5250 2250);
PAINT GREEN (-5250 2250);
DISPLAY INVISIBLE (-5250 2250);
FORCEPROP 1 LAST HDL_TAP TRUE
J 2
(-5575 2075);
DISPLAY 1.446809 (-5575 2075);
PAINT GREEN (-5575 2075);
DISPLAY INVISIBLE (-5575 2075);
FORCEPROP 1 LAST PATH I16
J 2
(-5248 2200);
DISPLAY 0.872340 (-5248 2200);
PAINT GREEN (-5248 2200);
DISPLAY INVISIBLE (-5248 2200);
FORCEADD TAP..1
R 2
(-5250 2150);
FORCEPROP 3 LASTPIN (-5200 2150) SIG_NAME UPI_CPU1_CPU0_P0P0_DN<8>
J 0
(-5190 2160);
DISPLAY 0.659574 (-5190 2160);
PAINT MONO (-5190 2160);
DISPLAY INVISIBLE (-5190 2160);
FORCEPROP 1 LASTPIN (-5200 2150) BN 8
J 2
(-5188 2158);
DISPLAY 0.617021 (-5188 2158);
PAINT PINK (-5188 2158);
FORCEPROP 2 LAST CDS_LIB mstr_standard
J 0
(-5250 2150);
PAINT MONO (-5250 2150);
DISPLAY INVISIBLE (-5250 2150);
FORCEPROP 1 LAST BODY_TYPE PLUMBING
J 2
(-5250 2200);
DISPLAY 1.446809 (-5250 2200);
PAINT GREEN (-5250 2200);
DISPLAY INVISIBLE (-5250 2200);
FORCEPROP 1 LAST HDL_TAP TRUE
J 2
(-5575 2025);
DISPLAY 1.446809 (-5575 2025);
PAINT GREEN (-5575 2025);
DISPLAY INVISIBLE (-5575 2025);
FORCEPROP 1 LAST PATH I17
J 2
(-5248 2150);
DISPLAY 0.872340 (-5248 2150);
PAINT GREEN (-5248 2150);
DISPLAY INVISIBLE (-5248 2150);
FORCEADD TAP..1
R 2
(-5250 2350);
FORCEPROP 3 LASTPIN (-5200 2350) SIG_NAME UPI_CPU1_CPU0_P0P0_DN<4>
J 0
(-5190 2360);
DISPLAY 0.659574 (-5190 2360);
PAINT MONO (-5190 2360);
DISPLAY INVISIBLE (-5190 2360);
FORCEPROP 1 LASTPIN (-5200 2350) BN 4
J 2
(-5188 2358);
DISPLAY 0.617021 (-5188 2358);
PAINT PINK (-5188 2358);
FORCEPROP 2 LAST CDS_LIB mstr_standard
J 0
(-5250 2350);
PAINT MONO (-5250 2350);
DISPLAY INVISIBLE (-5250 2350);
FORCEPROP 1 LAST BODY_TYPE PLUMBING
J 2
(-5250 2400);
DISPLAY 1.446809 (-5250 2400);
PAINT GREEN (-5250 2400);
DISPLAY INVISIBLE (-5250 2400);
FORCEPROP 1 LAST HDL_TAP TRUE
J 2
(-5575 2225);
DISPLAY 1.446809 (-5575 2225);
PAINT GREEN (-5575 2225);
DISPLAY INVISIBLE (-5575 2225);
FORCEPROP 1 LAST PATH I18
J 2
(-5248 2350);
DISPLAY 0.872340 (-5248 2350);
PAINT GREEN (-5248 2350);
DISPLAY INVISIBLE (-5248 2350);
FORCEADD TAP..1
R 2
(-5250 2300);
FORCEPROP 3 LASTPIN (-5200 2300) SIG_NAME UPI_CPU1_CPU0_P0P0_DN<5>
J 0
(-5190 2310);
DISPLAY 0.659574 (-5190 2310);
PAINT MONO (-5190 2310);
DISPLAY INVISIBLE (-5190 2310);
FORCEPROP 1 LASTPIN (-5200 2300) BN 5
J 2
(-5188 2308);
DISPLAY 0.617021 (-5188 2308);
PAINT PINK (-5188 2308);
FORCEPROP 2 LAST CDS_LIB mstr_standard
J 0
(-5250 2300);
PAINT MONO (-5250 2300);
DISPLAY INVISIBLE (-5250 2300);
FORCEPROP 1 LAST BODY_TYPE PLUMBING
J 2
(-5250 2350);
DISPLAY 1.446809 (-5250 2350);
PAINT GREEN (-5250 2350);
DISPLAY INVISIBLE (-5250 2350);
FORCEPROP 1 LAST HDL_TAP TRUE
J 2
(-5575 2175);
DISPLAY 1.446809 (-5575 2175);
PAINT GREEN (-5575 2175);
DISPLAY INVISIBLE (-5575 2175);
FORCEPROP 1 LAST PATH I19
J 2
(-5248 2300);
DISPLAY 0.872340 (-5248 2300);
PAINT GREEN (-5248 2300);
DISPLAY INVISIBLE (-5248 2300);
FORCEADD OFFPAGE..1
(-6450 3650);
FORCEPROP 2 LAST $XR0 67 
J 0
(-6701 3650);
DISPLAY 0.638298 (-6701 3650);
PAINT MONO (-6701 3650);
FORCEPROP 2 LAST CDS_LIB mstr_standard
J 0
(-6450 3650);
PAINT MONO (-6450 3650);
DISPLAY INVISIBLE (-6450 3650);
FORCEPROP 1 LAST OFFPAGE TRUE
J 0
(-6125 3525);
DISPLAY 1.170213 (-6125 3525);
PAINT GREEN (-6125 3525);
DISPLAY INVISIBLE (-6125 3525);
FORCEPROP 1 LAST COMMENT_BODY TRUE
J 0
(-6325 3550);
DISPLAY 1.170213 (-6325 3550);
PAINT GREEN (-6325 3550);
DISPLAY INVISIBLE (-6325 3550);
FORCEPROP 2 LAST PATH I2
J 0
(-6400 3725);
DISPLAY 1.021277 (-6400 3725);
PAINT ORANGE (-6400 3725);
DISPLAY INVISIBLE (-6400 3725);
FORCEADD TAP..1
R 2
(-5250 2500);
FORCEPROP 3 LASTPIN (-5200 2500) SIG_NAME UPI_CPU1_CPU0_P0P0_DN<1>
J 0
(-5190 2510);
DISPLAY 0.659574 (-5190 2510);
PAINT MONO (-5190 2510);
DISPLAY INVISIBLE (-5190 2510);
FORCEPROP 1 LASTPIN (-5200 2500) BN 1
J 2
(-5188 2508);
DISPLAY 0.617021 (-5188 2508);
PAINT PINK (-5188 2508);
FORCEPROP 2 LAST CDS_LIB mstr_standard
J 0
(-5250 2500);
PAINT MONO (-5250 2500);
DISPLAY INVISIBLE (-5250 2500);
FORCEPROP 1 LAST BODY_TYPE PLUMBING
J 2
(-5250 2550);
DISPLAY 1.446809 (-5250 2550);
PAINT GREEN (-5250 2550);
DISPLAY INVISIBLE (-5250 2550);
FORCEPROP 1 LAST HDL_TAP TRUE
J 2
(-5575 2375);
DISPLAY 1.446809 (-5575 2375);
PAINT GREEN (-5575 2375);
DISPLAY INVISIBLE (-5575 2375);
FORCEPROP 1 LAST PATH I20
J 2
(-5248 2500);
DISPLAY 0.872340 (-5248 2500);
PAINT GREEN (-5248 2500);
DISPLAY INVISIBLE (-5248 2500);
FORCEADD TAP..1
R 2
(-5250 2450);
FORCEPROP 3 LASTPIN (-5200 2450) SIG_NAME UPI_CPU1_CPU0_P0P0_DN<2>
J 0
(-5190 2460);
DISPLAY 0.659574 (-5190 2460);
PAINT MONO (-5190 2460);
DISPLAY INVISIBLE (-5190 2460);
FORCEPROP 1 LASTPIN (-5200 2450) BN 2
J 2
(-5188 2458);
DISPLAY 0.617021 (-5188 2458);
PAINT PINK (-5188 2458);
FORCEPROP 2 LAST CDS_LIB mstr_standard
J 0
(-5250 2450);
PAINT MONO (-5250 2450);
DISPLAY INVISIBLE (-5250 2450);
FORCEPROP 1 LAST BODY_TYPE PLUMBING
J 2
(-5250 2500);
DISPLAY 1.446809 (-5250 2500);
PAINT GREEN (-5250 2500);
DISPLAY INVISIBLE (-5250 2500);
FORCEPROP 1 LAST HDL_TAP TRUE
J 2
(-5575 2325);
DISPLAY 1.446809 (-5575 2325);
PAINT GREEN (-5575 2325);
DISPLAY INVISIBLE (-5575 2325);
FORCEPROP 1 LAST PATH I21
J 2
(-5248 2450);
DISPLAY 0.872340 (-5248 2450);
PAINT GREEN (-5248 2450);
DISPLAY INVISIBLE (-5248 2450);
FORCEADD TAP..1
R 2
(-5250 2400);
FORCEPROP 3 LASTPIN (-5200 2400) SIG_NAME UPI_CPU1_CPU0_P0P0_DN<3>
J 0
(-5190 2410);
DISPLAY 0.659574 (-5190 2410);
PAINT MONO (-5190 2410);
DISPLAY INVISIBLE (-5190 2410);
FORCEPROP 1 LASTPIN (-5200 2400) BN 3
J 2
(-5188 2408);
DISPLAY 0.617021 (-5188 2408);
PAINT PINK (-5188 2408);
FORCEPROP 2 LAST CDS_LIB mstr_standard
J 0
(-5250 2400);
PAINT MONO (-5250 2400);
DISPLAY INVISIBLE (-5250 2400);
FORCEPROP 1 LAST BODY_TYPE PLUMBING
J 2
(-5250 2450);
DISPLAY 1.446809 (-5250 2450);
PAINT GREEN (-5250 2450);
DISPLAY INVISIBLE (-5250 2450);
FORCEPROP 1 LAST HDL_TAP TRUE
J 2
(-5575 2275);
DISPLAY 1.446809 (-5575 2275);
PAINT GREEN (-5575 2275);
DISPLAY INVISIBLE (-5575 2275);
FORCEPROP 1 LAST PATH I22
J 2
(-5248 2400);
DISPLAY 0.872340 (-5248 2400);
PAINT GREEN (-5248 2400);
DISPLAY INVISIBLE (-5248 2400);
FORCEADD TAP..1
R 2
(-5250 2750);
FORCEPROP 3 LASTPIN (-5200 2750) SIG_NAME UPI_CPU1_CPU0_P0P0_DP<17>
J 0
(-5190 2760);
DISPLAY 0.659574 (-5190 2760);
PAINT MONO (-5190 2760);
DISPLAY INVISIBLE (-5190 2760);
FORCEPROP 1 LASTPIN (-5200 2750) BN 17
J 2
(-5188 2758);
DISPLAY 0.617021 (-5188 2758);
PAINT PINK (-5188 2758);
FORCEPROP 2 LAST CDS_LIB mstr_standard
J 0
(-5250 2750);
PAINT MONO (-5250 2750);
DISPLAY INVISIBLE (-5250 2750);
FORCEPROP 1 LAST BODY_TYPE PLUMBING
J 2
(-5250 2800);
DISPLAY 1.446809 (-5250 2800);
PAINT GREEN (-5250 2800);
DISPLAY INVISIBLE (-5250 2800);
FORCEPROP 1 LAST HDL_TAP TRUE
J 2
(-5575 2625);
DISPLAY 1.446809 (-5575 2625);
PAINT GREEN (-5575 2625);
DISPLAY INVISIBLE (-5575 2625);
FORCEPROP 1 LAST PATH I23
J 2
(-5248 2750);
DISPLAY 0.872340 (-5248 2750);
PAINT GREEN (-5248 2750);
DISPLAY INVISIBLE (-5248 2750);
FORCEADD TAP..1
R 2
(-5250 2650);
FORCEPROP 3 LASTPIN (-5200 2650) SIG_NAME UPI_CPU1_CPU0_P0P0_DP<19>
J 0
(-5190 2660);
DISPLAY 0.659574 (-5190 2660);
PAINT MONO (-5190 2660);
DISPLAY INVISIBLE (-5190 2660);
FORCEPROP 1 LASTPIN (-5200 2650) BN 19
J 2
(-5188 2658);
DISPLAY 0.617021 (-5188 2658);
PAINT PINK (-5188 2658);
FORCEPROP 2 LAST CDS_LIB mstr_standard
J 0
(-5250 2650);
PAINT MONO (-5250 2650);
DISPLAY INVISIBLE (-5250 2650);
FORCEPROP 1 LAST BODY_TYPE PLUMBING
J 2
(-5250 2700);
DISPLAY 1.446809 (-5250 2700);
PAINT GREEN (-5250 2700);
DISPLAY INVISIBLE (-5250 2700);
FORCEPROP 1 LAST HDL_TAP TRUE
J 2
(-5575 2525);
DISPLAY 1.446809 (-5575 2525);
PAINT GREEN (-5575 2525);
DISPLAY INVISIBLE (-5575 2525);
FORCEPROP 1 LAST PATH I24
J 2
(-5248 2650);
DISPLAY 0.872340 (-5248 2650);
PAINT GREEN (-5248 2650);
DISPLAY INVISIBLE (-5248 2650);
FORCEADD TAP..1
R 2
(-5250 2700);
FORCEPROP 3 LASTPIN (-5200 2700) SIG_NAME UPI_CPU1_CPU0_P0P0_DP<18>
J 0
(-5190 2710);
DISPLAY 0.659574 (-5190 2710);
PAINT MONO (-5190 2710);
DISPLAY INVISIBLE (-5190 2710);
FORCEPROP 1 LASTPIN (-5200 2700) BN 18
J 2
(-5188 2708);
DISPLAY 0.617021 (-5188 2708);
PAINT PINK (-5188 2708);
FORCEPROP 2 LAST CDS_LIB mstr_standard
J 0
(-5250 2700);
PAINT MONO (-5250 2700);
DISPLAY INVISIBLE (-5250 2700);
FORCEPROP 1 LAST BODY_TYPE PLUMBING
J 2
(-5250 2750);
DISPLAY 1.446809 (-5250 2750);
PAINT GREEN (-5250 2750);
DISPLAY INVISIBLE (-5250 2750);
FORCEPROP 1 LAST HDL_TAP TRUE
J 2
(-5575 2575);
DISPLAY 1.446809 (-5575 2575);
PAINT GREEN (-5575 2575);
DISPLAY INVISIBLE (-5575 2575);
FORCEPROP 1 LAST PATH I25
J 2
(-5248 2700);
DISPLAY 0.872340 (-5248 2700);
PAINT GREEN (-5248 2700);
DISPLAY INVISIBLE (-5248 2700);
FORCEADD TAP..1
R 2
(-5250 2550);
FORCEPROP 3 LASTPIN (-5200 2550) SIG_NAME UPI_CPU1_CPU0_P0P0_DN<0>
J 0
(-5190 2560);
DISPLAY 0.659574 (-5190 2560);
PAINT MONO (-5190 2560);
DISPLAY INVISIBLE (-5190 2560);
FORCEPROP 1 LASTPIN (-5200 2550) BN 0
J 2
(-5188 2558);
DISPLAY 0.617021 (-5188 2558);
PAINT PINK (-5188 2558);
FORCEPROP 2 LAST CDS_LIB mstr_standard
J 0
(-5250 2550);
PAINT MONO (-5250 2550);
DISPLAY INVISIBLE (-5250 2550);
FORCEPROP 1 LAST BODY_TYPE PLUMBING
J 2
(-5250 2600);
DISPLAY 1.446809 (-5250 2600);
PAINT GREEN (-5250 2600);
DISPLAY INVISIBLE (-5250 2600);
FORCEPROP 1 LAST HDL_TAP TRUE
J 2
(-5575 2425);
DISPLAY 1.446809 (-5575 2425);
PAINT GREEN (-5575 2425);
DISPLAY INVISIBLE (-5575 2425);
FORCEPROP 1 LAST PATH I26
J 2
(-5248 2550);
DISPLAY 0.872340 (-5248 2550);
PAINT GREEN (-5248 2550);
DISPLAY INVISIBLE (-5248 2550);
FORCEADD TAP..1
R 2
(-5250 2850);
FORCEPROP 3 LASTPIN (-5200 2850) SIG_NAME UPI_CPU1_CPU0_P0P0_DP<15>
J 0
(-5190 2860);
DISPLAY 0.659574 (-5190 2860);
PAINT MONO (-5190 2860);
DISPLAY INVISIBLE (-5190 2860);
FORCEPROP 1 LASTPIN (-5200 2850) BN 15
J 2
(-5188 2858);
DISPLAY 0.617021 (-5188 2858);
PAINT PINK (-5188 2858);
FORCEPROP 2 LAST CDS_LIB mstr_standard
J 0
(-5250 2850);
PAINT MONO (-5250 2850);
DISPLAY INVISIBLE (-5250 2850);
FORCEPROP 1 LAST BODY_TYPE PLUMBING
J 2
(-5250 2900);
DISPLAY 1.446809 (-5250 2900);
PAINT GREEN (-5250 2900);
DISPLAY INVISIBLE (-5250 2900);
FORCEPROP 1 LAST HDL_TAP TRUE
J 2
(-5575 2725);
DISPLAY 1.446809 (-5575 2725);
PAINT GREEN (-5575 2725);
DISPLAY INVISIBLE (-5575 2725);
FORCEPROP 1 LAST PATH I27
J 2
(-5248 2850);
DISPLAY 0.872340 (-5248 2850);
PAINT GREEN (-5248 2850);
DISPLAY INVISIBLE (-5248 2850);
FORCEADD TAP..1
R 2
(-5250 2800);
FORCEPROP 3 LASTPIN (-5200 2800) SIG_NAME UPI_CPU1_CPU0_P0P0_DP<16>
J 0
(-5190 2810);
DISPLAY 0.659574 (-5190 2810);
PAINT MONO (-5190 2810);
DISPLAY INVISIBLE (-5190 2810);
FORCEPROP 1 LASTPIN (-5200 2800) BN 16
J 2
(-5188 2808);
DISPLAY 0.617021 (-5188 2808);
PAINT PINK (-5188 2808);
FORCEPROP 2 LAST CDS_LIB mstr_standard
J 0
(-5250 2800);
PAINT MONO (-5250 2800);
DISPLAY INVISIBLE (-5250 2800);
FORCEPROP 1 LAST BODY_TYPE PLUMBING
J 2
(-5250 2850);
DISPLAY 1.446809 (-5250 2850);
PAINT GREEN (-5250 2850);
DISPLAY INVISIBLE (-5250 2850);
FORCEPROP 1 LAST HDL_TAP TRUE
J 2
(-5575 2675);
DISPLAY 1.446809 (-5575 2675);
PAINT GREEN (-5575 2675);
DISPLAY INVISIBLE (-5575 2675);
FORCEPROP 1 LAST PATH I28
J 2
(-5248 2800);
DISPLAY 0.872340 (-5248 2800);
PAINT GREEN (-5248 2800);
DISPLAY INVISIBLE (-5248 2800);
FORCEADD TAP..1
R 2
(-5250 2950);
FORCEPROP 3 LASTPIN (-5200 2950) SIG_NAME UPI_CPU1_CPU0_P0P0_DP<13>
J 0
(-5190 2960);
DISPLAY 0.659574 (-5190 2960);
PAINT MONO (-5190 2960);
DISPLAY INVISIBLE (-5190 2960);
FORCEPROP 1 LASTPIN (-5200 2950) BN 13
J 2
(-5188 2958);
DISPLAY 0.617021 (-5188 2958);
PAINT PINK (-5188 2958);
FORCEPROP 2 LAST CDS_LIB mstr_standard
J 0
(-5250 2950);
PAINT MONO (-5250 2950);
DISPLAY INVISIBLE (-5250 2950);
FORCEPROP 1 LAST BODY_TYPE PLUMBING
J 2
(-5250 3000);
DISPLAY 1.446809 (-5250 3000);
PAINT GREEN (-5250 3000);
DISPLAY INVISIBLE (-5250 3000);
FORCEPROP 1 LAST HDL_TAP TRUE
J 2
(-5575 2825);
DISPLAY 1.446809 (-5575 2825);
PAINT GREEN (-5575 2825);
DISPLAY INVISIBLE (-5575 2825);
FORCEPROP 1 LAST PATH I29
J 2
(-5248 2950);
DISPLAY 0.872340 (-5248 2950);
PAINT GREEN (-5248 2950);
DISPLAY INVISIBLE (-5248 2950);
FORCEADD TAP..1
R 2
(-5250 1600);
FORCEPROP 3 LASTPIN (-5200 1600) SIG_NAME UPI_CPU1_CPU0_P0P0_DN<19>
J 0
(-5190 1610);
DISPLAY 0.659574 (-5190 1610);
PAINT MONO (-5190 1610);
DISPLAY INVISIBLE (-5190 1610);
FORCEPROP 1 LASTPIN (-5200 1600) BN 19
J 2
(-5188 1608);
DISPLAY 0.617021 (-5188 1608);
PAINT PINK (-5188 1608);
FORCEPROP 2 LAST CDS_LIB mstr_standard
J 0
(-5250 1600);
PAINT MONO (-5250 1600);
DISPLAY INVISIBLE (-5250 1600);
FORCEPROP 1 LAST BODY_TYPE PLUMBING
J 2
(-5250 1650);
DISPLAY 1.446809 (-5250 1650);
PAINT GREEN (-5250 1650);
DISPLAY INVISIBLE (-5250 1650);
FORCEPROP 1 LAST HDL_TAP TRUE
J 2
(-5575 1475);
DISPLAY 1.446809 (-5575 1475);
PAINT GREEN (-5575 1475);
DISPLAY INVISIBLE (-5575 1475);
FORCEPROP 1 LAST PATH I3
J 2
(-5248 1600);
DISPLAY 0.872340 (-5248 1600);
PAINT GREEN (-5248 1600);
DISPLAY INVISIBLE (-5248 1600);
FORCEADD TAP..1
R 2
(-5250 3000);
FORCEPROP 3 LASTPIN (-5200 3000) SIG_NAME UPI_CPU1_CPU0_P0P0_DP<12>
J 0
(-5190 3010);
DISPLAY 0.659574 (-5190 3010);
PAINT MONO (-5190 3010);
DISPLAY INVISIBLE (-5190 3010);
FORCEPROP 1 LASTPIN (-5200 3000) BN 12
J 2
(-5188 3008);
DISPLAY 0.617021 (-5188 3008);
PAINT PINK (-5188 3008);
FORCEPROP 2 LAST CDS_LIB mstr_standard
J 0
(-5250 3000);
PAINT MONO (-5250 3000);
DISPLAY INVISIBLE (-5250 3000);
FORCEPROP 1 LAST BODY_TYPE PLUMBING
J 2
(-5250 3050);
DISPLAY 1.446809 (-5250 3050);
PAINT GREEN (-5250 3050);
DISPLAY INVISIBLE (-5250 3050);
FORCEPROP 1 LAST HDL_TAP TRUE
J 2
(-5575 2875);
DISPLAY 1.446809 (-5575 2875);
PAINT GREEN (-5575 2875);
DISPLAY INVISIBLE (-5575 2875);
FORCEPROP 1 LAST PATH I30
J 2
(-5248 3000);
DISPLAY 0.872340 (-5248 3000);
PAINT GREEN (-5248 3000);
DISPLAY INVISIBLE (-5248 3000);
FORCEADD TAP..1
R 2
(-5250 2900);
FORCEPROP 3 LASTPIN (-5200 2900) SIG_NAME UPI_CPU1_CPU0_P0P0_DP<14>
J 0
(-5190 2910);
DISPLAY 0.659574 (-5190 2910);
PAINT MONO (-5190 2910);
DISPLAY INVISIBLE (-5190 2910);
FORCEPROP 1 LASTPIN (-5200 2900) BN 14
J 2
(-5188 2908);
DISPLAY 0.617021 (-5188 2908);
PAINT PINK (-5188 2908);
FORCEPROP 2 LAST CDS_LIB mstr_standard
J 0
(-5250 2900);
PAINT MONO (-5250 2900);
DISPLAY INVISIBLE (-5250 2900);
FORCEPROP 1 LAST BODY_TYPE PLUMBING
J 2
(-5250 2950);
DISPLAY 1.446809 (-5250 2950);
PAINT GREEN (-5250 2950);
DISPLAY INVISIBLE (-5250 2950);
FORCEPROP 1 LAST HDL_TAP TRUE
J 2
(-5575 2775);
DISPLAY 1.446809 (-5575 2775);
PAINT GREEN (-5575 2775);
DISPLAY INVISIBLE (-5575 2775);
FORCEPROP 1 LAST PATH I31
J 2
(-5248 2900);
DISPLAY 0.872340 (-5248 2900);
PAINT GREEN (-5248 2900);
DISPLAY INVISIBLE (-5248 2900);
FORCEADD TAP..1
R 2
(-5250 3050);
FORCEPROP 3 LASTPIN (-5200 3050) SIG_NAME UPI_CPU1_CPU0_P0P0_DP<11>
J 0
(-5190 3060);
DISPLAY 0.659574 (-5190 3060);
PAINT MONO (-5190 3060);
DISPLAY INVISIBLE (-5190 3060);
FORCEPROP 1 LASTPIN (-5200 3050) BN 11
J 2
(-5188 3058);
DISPLAY 0.617021 (-5188 3058);
PAINT PINK (-5188 3058);
FORCEPROP 2 LAST CDS_LIB mstr_standard
J 0
(-5250 3050);
PAINT MONO (-5250 3050);
DISPLAY INVISIBLE (-5250 3050);
FORCEPROP 1 LAST BODY_TYPE PLUMBING
J 2
(-5250 3100);
DISPLAY 1.446809 (-5250 3100);
PAINT GREEN (-5250 3100);
DISPLAY INVISIBLE (-5250 3100);
FORCEPROP 1 LAST HDL_TAP TRUE
J 2
(-5575 2925);
DISPLAY 1.446809 (-5575 2925);
PAINT GREEN (-5575 2925);
DISPLAY INVISIBLE (-5575 2925);
FORCEPROP 1 LAST PATH I32
J 2
(-5248 3050);
DISPLAY 0.872340 (-5248 3050);
PAINT GREEN (-5248 3050);
DISPLAY INVISIBLE (-5248 3050);
FORCEADD TAP..1
R 2
(-5250 3100);
FORCEPROP 3 LASTPIN (-5200 3100) SIG_NAME UPI_CPU1_CPU0_P0P0_DP<10>
J 0
(-5190 3110);
DISPLAY 0.659574 (-5190 3110);
PAINT MONO (-5190 3110);
DISPLAY INVISIBLE (-5190 3110);
FORCEPROP 1 LASTPIN (-5200 3100) BN 10
J 2
(-5188 3108);
DISPLAY 0.617021 (-5188 3108);
PAINT PINK (-5188 3108);
FORCEPROP 2 LAST CDS_LIB mstr_standard
J 0
(-5250 3100);
PAINT MONO (-5250 3100);
DISPLAY INVISIBLE (-5250 3100);
FORCEPROP 1 LAST BODY_TYPE PLUMBING
J 2
(-5250 3150);
DISPLAY 1.446809 (-5250 3150);
PAINT GREEN (-5250 3150);
DISPLAY INVISIBLE (-5250 3150);
FORCEPROP 1 LAST HDL_TAP TRUE
J 2
(-5575 2975);
DISPLAY 1.446809 (-5575 2975);
PAINT GREEN (-5575 2975);
DISPLAY INVISIBLE (-5575 2975);
FORCEPROP 1 LAST PATH I33
J 2
(-5248 3100);
DISPLAY 0.872340 (-5248 3100);
PAINT GREEN (-5248 3100);
DISPLAY INVISIBLE (-5248 3100);
FORCEADD TAP..1
R 2
(-5250 3150);
FORCEPROP 3 LASTPIN (-5200 3150) SIG_NAME UPI_CPU1_CPU0_P0P0_DP<9>
J 0
(-5190 3160);
DISPLAY 0.659574 (-5190 3160);
PAINT MONO (-5190 3160);
DISPLAY INVISIBLE (-5190 3160);
FORCEPROP 1 LASTPIN (-5200 3150) BN 9
J 2
(-5188 3158);
DISPLAY 0.617021 (-5188 3158);
PAINT PINK (-5188 3158);
FORCEPROP 2 LAST CDS_LIB mstr_standard
J 0
(-5250 3150);
PAINT MONO (-5250 3150);
DISPLAY INVISIBLE (-5250 3150);
FORCEPROP 1 LAST BODY_TYPE PLUMBING
J 2
(-5250 3200);
DISPLAY 1.446809 (-5250 3200);
PAINT GREEN (-5250 3200);
DISPLAY INVISIBLE (-5250 3200);
FORCEPROP 1 LAST HDL_TAP TRUE
J 2
(-5575 3025);
DISPLAY 1.446809 (-5575 3025);
PAINT GREEN (-5575 3025);
DISPLAY INVISIBLE (-5575 3025);
FORCEPROP 1 LAST PATH I34
J 2
(-5248 3150);
DISPLAY 0.872340 (-5248 3150);
PAINT GREEN (-5248 3150);
DISPLAY INVISIBLE (-5248 3150);
FORCEADD TAP..1
R 2
(-5250 3250);
FORCEPROP 3 LASTPIN (-5200 3250) SIG_NAME UPI_CPU1_CPU0_P0P0_DP<7>
J 0
(-5190 3260);
DISPLAY 0.659574 (-5190 3260);
PAINT MONO (-5190 3260);
DISPLAY INVISIBLE (-5190 3260);
FORCEPROP 1 LASTPIN (-5200 3250) BN 7
J 2
(-5188 3258);
DISPLAY 0.617021 (-5188 3258);
PAINT PINK (-5188 3258);
FORCEPROP 2 LAST CDS_LIB mstr_standard
J 0
(-5250 3250);
PAINT MONO (-5250 3250);
DISPLAY INVISIBLE (-5250 3250);
FORCEPROP 1 LAST BODY_TYPE PLUMBING
J 2
(-5250 3300);
DISPLAY 1.446809 (-5250 3300);
PAINT GREEN (-5250 3300);
DISPLAY INVISIBLE (-5250 3300);
FORCEPROP 1 LAST HDL_TAP TRUE
J 2
(-5575 3125);
DISPLAY 1.446809 (-5575 3125);
PAINT GREEN (-5575 3125);
DISPLAY INVISIBLE (-5575 3125);
FORCEPROP 1 LAST PATH I35
J 2
(-5248 3250);
DISPLAY 0.872340 (-5248 3250);
PAINT GREEN (-5248 3250);
DISPLAY INVISIBLE (-5248 3250);
FORCEADD TAP..1
R 2
(-5250 3200);
FORCEPROP 3 LASTPIN (-5200 3200) SIG_NAME UPI_CPU1_CPU0_P0P0_DP<8>
J 0
(-5190 3210);
DISPLAY 0.659574 (-5190 3210);
PAINT MONO (-5190 3210);
DISPLAY INVISIBLE (-5190 3210);
FORCEPROP 1 LASTPIN (-5200 3200) BN 8
J 2
(-5188 3208);
DISPLAY 0.617021 (-5188 3208);
PAINT PINK (-5188 3208);
FORCEPROP 2 LAST CDS_LIB mstr_standard
J 0
(-5250 3200);
PAINT MONO (-5250 3200);
DISPLAY INVISIBLE (-5250 3200);
FORCEPROP 1 LAST BODY_TYPE PLUMBING
J 2
(-5250 3250);
DISPLAY 1.446809 (-5250 3250);
PAINT GREEN (-5250 3250);
DISPLAY INVISIBLE (-5250 3250);
FORCEPROP 1 LAST HDL_TAP TRUE
J 2
(-5575 3075);
DISPLAY 1.446809 (-5575 3075);
PAINT GREEN (-5575 3075);
DISPLAY INVISIBLE (-5575 3075);
FORCEPROP 1 LAST PATH I36
J 2
(-5248 3200);
DISPLAY 0.872340 (-5248 3200);
PAINT GREEN (-5248 3200);
DISPLAY INVISIBLE (-5248 3200);
FORCEADD TAP..1
R 2
(-5250 3300);
FORCEPROP 3 LASTPIN (-5200 3300) SIG_NAME UPI_CPU1_CPU0_P0P0_DP<6>
J 0
(-5190 3310);
DISPLAY 0.659574 (-5190 3310);
PAINT MONO (-5190 3310);
DISPLAY INVISIBLE (-5190 3310);
FORCEPROP 1 LASTPIN (-5200 3300) BN 6
J 2
(-5188 3308);
DISPLAY 0.617021 (-5188 3308);
PAINT PINK (-5188 3308);
FORCEPROP 2 LAST CDS_LIB mstr_standard
J 0
(-5250 3300);
PAINT MONO (-5250 3300);
DISPLAY INVISIBLE (-5250 3300);
FORCEPROP 1 LAST BODY_TYPE PLUMBING
J 2
(-5250 3350);
DISPLAY 1.446809 (-5250 3350);
PAINT GREEN (-5250 3350);
DISPLAY INVISIBLE (-5250 3350);
FORCEPROP 1 LAST HDL_TAP TRUE
J 2
(-5575 3175);
DISPLAY 1.446809 (-5575 3175);
PAINT GREEN (-5575 3175);
DISPLAY INVISIBLE (-5575 3175);
FORCEPROP 1 LAST PATH I37
J 2
(-5248 3300);
DISPLAY 0.872340 (-5248 3300);
PAINT GREEN (-5248 3300);
DISPLAY INVISIBLE (-5248 3300);
FORCEADD TAP..1
R 2
(-5250 3400);
FORCEPROP 3 LASTPIN (-5200 3400) SIG_NAME UPI_CPU1_CPU0_P0P0_DP<4>
J 0
(-5190 3410);
DISPLAY 0.659574 (-5190 3410);
PAINT MONO (-5190 3410);
DISPLAY INVISIBLE (-5190 3410);
FORCEPROP 1 LASTPIN (-5200 3400) BN 4
J 2
(-5188 3408);
DISPLAY 0.617021 (-5188 3408);
PAINT PINK (-5188 3408);
FORCEPROP 2 LAST CDS_LIB mstr_standard
J 0
(-5250 3400);
PAINT MONO (-5250 3400);
DISPLAY INVISIBLE (-5250 3400);
FORCEPROP 1 LAST BODY_TYPE PLUMBING
J 2
(-5250 3450);
DISPLAY 1.446809 (-5250 3450);
PAINT GREEN (-5250 3450);
DISPLAY INVISIBLE (-5250 3450);
FORCEPROP 1 LAST HDL_TAP TRUE
J 2
(-5575 3275);
DISPLAY 1.446809 (-5575 3275);
PAINT GREEN (-5575 3275);
DISPLAY INVISIBLE (-5575 3275);
FORCEPROP 1 LAST PATH I38
J 2
(-5248 3400);
DISPLAY 0.872340 (-5248 3400);
PAINT GREEN (-5248 3400);
DISPLAY INVISIBLE (-5248 3400);
FORCEADD TAP..1
R 2
(-5250 3350);
FORCEPROP 3 LASTPIN (-5200 3350) SIG_NAME UPI_CPU1_CPU0_P0P0_DP<5>
J 0
(-5190 3360);
DISPLAY 0.659574 (-5190 3360);
PAINT MONO (-5190 3360);
DISPLAY INVISIBLE (-5190 3360);
FORCEPROP 1 LASTPIN (-5200 3350) BN 5
J 2
(-5188 3358);
DISPLAY 0.617021 (-5188 3358);
PAINT PINK (-5188 3358);
FORCEPROP 2 LAST CDS_LIB mstr_standard
J 0
(-5250 3350);
PAINT MONO (-5250 3350);
DISPLAY INVISIBLE (-5250 3350);
FORCEPROP 1 LAST BODY_TYPE PLUMBING
J 2
(-5250 3400);
DISPLAY 1.446809 (-5250 3400);
PAINT GREEN (-5250 3400);
DISPLAY INVISIBLE (-5250 3400);
FORCEPROP 1 LAST HDL_TAP TRUE
J 2
(-5575 3225);
DISPLAY 1.446809 (-5575 3225);
PAINT GREEN (-5575 3225);
DISPLAY INVISIBLE (-5575 3225);
FORCEPROP 1 LAST PATH I39
J 2
(-5248 3350);
DISPLAY 0.872340 (-5248 3350);
PAINT GREEN (-5248 3350);
DISPLAY INVISIBLE (-5248 3350);
FORCEADD TAP..1
R 2
(-5250 1700);
FORCEPROP 3 LASTPIN (-5200 1700) SIG_NAME UPI_CPU1_CPU0_P0P0_DN<17>
J 0
(-5190 1710);
DISPLAY 0.659574 (-5190 1710);
PAINT MONO (-5190 1710);
DISPLAY INVISIBLE (-5190 1710);
FORCEPROP 1 LASTPIN (-5200 1700) BN 17
J 2
(-5188 1708);
DISPLAY 0.617021 (-5188 1708);
PAINT PINK (-5188 1708);
FORCEPROP 2 LAST CDS_LIB mstr_standard
J 0
(-5250 1700);
PAINT MONO (-5250 1700);
DISPLAY INVISIBLE (-5250 1700);
FORCEPROP 1 LAST BODY_TYPE PLUMBING
J 2
(-5250 1750);
DISPLAY 1.446809 (-5250 1750);
PAINT GREEN (-5250 1750);
DISPLAY INVISIBLE (-5250 1750);
FORCEPROP 1 LAST HDL_TAP TRUE
J 2
(-5575 1575);
DISPLAY 1.446809 (-5575 1575);
PAINT GREEN (-5575 1575);
DISPLAY INVISIBLE (-5575 1575);
FORCEPROP 1 LAST PATH I4
J 2
(-5248 1700);
DISPLAY 0.872340 (-5248 1700);
PAINT GREEN (-5248 1700);
DISPLAY INVISIBLE (-5248 1700);
FORCEADD TAP..1
R 2
(-5250 3500);
FORCEPROP 3 LASTPIN (-5200 3500) SIG_NAME UPI_CPU1_CPU0_P0P0_DP<2>
J 0
(-5190 3510);
DISPLAY 0.659574 (-5190 3510);
PAINT MONO (-5190 3510);
DISPLAY INVISIBLE (-5190 3510);
FORCEPROP 1 LASTPIN (-5200 3500) BN 2
J 2
(-5188 3508);
DISPLAY 0.617021 (-5188 3508);
PAINT PINK (-5188 3508);
FORCEPROP 2 LAST CDS_LIB mstr_standard
J 0
(-5250 3500);
PAINT MONO (-5250 3500);
DISPLAY INVISIBLE (-5250 3500);
FORCEPROP 1 LAST BODY_TYPE PLUMBING
J 2
(-5250 3550);
DISPLAY 1.446809 (-5250 3550);
PAINT GREEN (-5250 3550);
DISPLAY INVISIBLE (-5250 3550);
FORCEPROP 1 LAST HDL_TAP TRUE
J 2
(-5575 3375);
DISPLAY 1.446809 (-5575 3375);
PAINT GREEN (-5575 3375);
DISPLAY INVISIBLE (-5575 3375);
FORCEPROP 1 LAST PATH I40
J 2
(-5248 3500);
DISPLAY 0.872340 (-5248 3500);
PAINT GREEN (-5248 3500);
DISPLAY INVISIBLE (-5248 3500);
FORCEADD TAP..1
R 2
(-5250 3450);
FORCEPROP 3 LASTPIN (-5200 3450) SIG_NAME UPI_CPU1_CPU0_P0P0_DP<3>
J 0
(-5190 3460);
DISPLAY 0.659574 (-5190 3460);
PAINT MONO (-5190 3460);
DISPLAY INVISIBLE (-5190 3460);
FORCEPROP 1 LASTPIN (-5200 3450) BN 3
J 2
(-5188 3458);
DISPLAY 0.617021 (-5188 3458);
PAINT PINK (-5188 3458);
FORCEPROP 2 LAST CDS_LIB mstr_standard
J 0
(-5250 3450);
PAINT MONO (-5250 3450);
DISPLAY INVISIBLE (-5250 3450);
FORCEPROP 1 LAST BODY_TYPE PLUMBING
J 2
(-5250 3500);
DISPLAY 1.446809 (-5250 3500);
PAINT GREEN (-5250 3500);
DISPLAY INVISIBLE (-5250 3500);
FORCEPROP 1 LAST HDL_TAP TRUE
J 2
(-5575 3325);
DISPLAY 1.446809 (-5575 3325);
PAINT GREEN (-5575 3325);
DISPLAY INVISIBLE (-5575 3325);
FORCEPROP 1 LAST PATH I41
J 2
(-5248 3450);
DISPLAY 0.872340 (-5248 3450);
PAINT GREEN (-5248 3450);
DISPLAY INVISIBLE (-5248 3450);
FORCEADD TAP..1
R 2
(-5250 3550);
FORCEPROP 3 LASTPIN (-5200 3550) SIG_NAME UPI_CPU1_CPU0_P0P0_DP<1>
J 0
(-5190 3560);
DISPLAY 0.659574 (-5190 3560);
PAINT MONO (-5190 3560);
DISPLAY INVISIBLE (-5190 3560);
FORCEPROP 1 LASTPIN (-5200 3550) BN 1
J 2
(-5188 3558);
DISPLAY 0.617021 (-5188 3558);
PAINT PINK (-5188 3558);
FORCEPROP 2 LAST CDS_LIB mstr_standard
J 0
(-5250 3550);
PAINT MONO (-5250 3550);
DISPLAY INVISIBLE (-5250 3550);
FORCEPROP 1 LAST BODY_TYPE PLUMBING
J 2
(-5250 3600);
DISPLAY 1.446809 (-5250 3600);
PAINT GREEN (-5250 3600);
DISPLAY INVISIBLE (-5250 3600);
FORCEPROP 1 LAST HDL_TAP TRUE
J 2
(-5575 3425);
DISPLAY 1.446809 (-5575 3425);
PAINT GREEN (-5575 3425);
DISPLAY INVISIBLE (-5575 3425);
FORCEPROP 1 LAST PATH I42
J 2
(-5248 3550);
DISPLAY 0.872340 (-5248 3550);
PAINT GREEN (-5248 3550);
DISPLAY INVISIBLE (-5248 3550);
FORCEADD TAP..1
R 2
(-5250 3600);
FORCEPROP 3 LASTPIN (-5200 3600) SIG_NAME UPI_CPU1_CPU0_P0P0_DP<0>
J 0
(-5190 3610);
DISPLAY 0.659574 (-5190 3610);
PAINT MONO (-5190 3610);
DISPLAY INVISIBLE (-5190 3610);
FORCEPROP 1 LASTPIN (-5200 3600) BN 0
J 2
(-5188 3608);
DISPLAY 0.617021 (-5188 3608);
PAINT PINK (-5188 3608);
FORCEPROP 2 LAST CDS_LIB mstr_standard
J 0
(-5250 3600);
PAINT MONO (-5250 3600);
DISPLAY INVISIBLE (-5250 3600);
FORCEPROP 1 LAST BODY_TYPE PLUMBING
J 2
(-5250 3650);
DISPLAY 1.446809 (-5250 3650);
PAINT GREEN (-5250 3650);
DISPLAY INVISIBLE (-5250 3650);
FORCEPROP 1 LAST HDL_TAP TRUE
J 2
(-5575 3475);
DISPLAY 1.446809 (-5575 3475);
PAINT GREEN (-5575 3475);
DISPLAY INVISIBLE (-5575 3475);
FORCEPROP 1 LAST PATH I43
J 2
(-5248 3600);
DISPLAY 0.872340 (-5248 3600);
PAINT GREEN (-5248 3600);
DISPLAY INVISIBLE (-5248 3600);
FORCEADD TAP..1
(-2925 1600);
FORCEPROP 3 LASTPIN (-2975 1600) SIG_NAME UPI_CPU0_CPU1_P0P0_DN<19>
J 0
(-2965 1610);
DISPLAY 0.659574 (-2965 1610);
PAINT MONO (-2965 1610);
DISPLAY INVISIBLE (-2965 1610);
FORCEPROP 1 LASTPIN (-2975 1600) BN 19
J 0
(-2987 1608);
DISPLAY 0.617021 (-2987 1608);
PAINT PINK (-2987 1608);
FORCEPROP 2 LAST CDS_LIB mstr_standard
J 0
(-2925 1600);
PAINT MONO (-2925 1600);
DISPLAY INVISIBLE (-2925 1600);
FORCEPROP 1 LAST BODY_TYPE PLUMBING
J 0
(-2925 1650);
DISPLAY 1.446809 (-2925 1650);
PAINT GREEN (-2925 1650);
DISPLAY INVISIBLE (-2925 1650);
FORCEPROP 1 LAST HDL_TAP TRUE
J 0
(-2600 1475);
DISPLAY 1.446809 (-2600 1475);
PAINT GREEN (-2600 1475);
DISPLAY INVISIBLE (-2600 1475);
FORCEPROP 1 LAST PATH I44
J 0
(-2927 1600);
DISPLAY 0.872340 (-2927 1600);
PAINT GREEN (-2927 1600);
DISPLAY INVISIBLE (-2927 1600);
FORCEADD TAP..1
(-2925 1750);
FORCEPROP 3 LASTPIN (-2975 1750) SIG_NAME UPI_CPU0_CPU1_P0P0_DN<16>
J 0
(-2965 1760);
DISPLAY 0.659574 (-2965 1760);
PAINT MONO (-2965 1760);
DISPLAY INVISIBLE (-2965 1760);
FORCEPROP 1 LASTPIN (-2975 1750) BN 16
J 0
(-2987 1758);
DISPLAY 0.617021 (-2987 1758);
PAINT PINK (-2987 1758);
FORCEPROP 2 LAST CDS_LIB mstr_standard
J 0
(-2925 1750);
PAINT MONO (-2925 1750);
DISPLAY INVISIBLE (-2925 1750);
FORCEPROP 1 LAST BODY_TYPE PLUMBING
J 0
(-2925 1800);
DISPLAY 1.446809 (-2925 1800);
PAINT GREEN (-2925 1800);
DISPLAY INVISIBLE (-2925 1800);
FORCEPROP 1 LAST HDL_TAP TRUE
J 0
(-2600 1625);
DISPLAY 1.446809 (-2600 1625);
PAINT GREEN (-2600 1625);
DISPLAY INVISIBLE (-2600 1625);
FORCEPROP 1 LAST PATH I45
J 0
(-2927 1750);
DISPLAY 0.872340 (-2927 1750);
PAINT GREEN (-2927 1750);
DISPLAY INVISIBLE (-2927 1750);
FORCEADD TAP..1
(-2925 1700);
FORCEPROP 3 LASTPIN (-2975 1700) SIG_NAME UPI_CPU0_CPU1_P0P0_DN<17>
J 0
(-2965 1710);
DISPLAY 0.659574 (-2965 1710);
PAINT MONO (-2965 1710);
DISPLAY INVISIBLE (-2965 1710);
FORCEPROP 1 LASTPIN (-2975 1700) BN 17
J 0
(-2987 1708);
DISPLAY 0.617021 (-2987 1708);
PAINT PINK (-2987 1708);
FORCEPROP 2 LAST CDS_LIB mstr_standard
J 0
(-2925 1700);
PAINT MONO (-2925 1700);
DISPLAY INVISIBLE (-2925 1700);
FORCEPROP 1 LAST BODY_TYPE PLUMBING
J 0
(-2925 1750);
DISPLAY 1.446809 (-2925 1750);
PAINT GREEN (-2925 1750);
DISPLAY INVISIBLE (-2925 1750);
FORCEPROP 1 LAST HDL_TAP TRUE
J 0
(-2600 1575);
DISPLAY 1.446809 (-2600 1575);
PAINT GREEN (-2600 1575);
DISPLAY INVISIBLE (-2600 1575);
FORCEPROP 1 LAST PATH I46
J 0
(-2927 1700);
DISPLAY 0.872340 (-2927 1700);
PAINT GREEN (-2927 1700);
DISPLAY INVISIBLE (-2927 1700);
FORCEADD TAP..1
(-2925 1650);
FORCEPROP 3 LASTPIN (-2975 1650) SIG_NAME UPI_CPU0_CPU1_P0P0_DN<18>
J 0
(-2965 1660);
DISPLAY 0.659574 (-2965 1660);
PAINT MONO (-2965 1660);
DISPLAY INVISIBLE (-2965 1660);
FORCEPROP 1 LASTPIN (-2975 1650) BN 18
J 0
(-2987 1658);
DISPLAY 0.617021 (-2987 1658);
PAINT PINK (-2987 1658);
FORCEPROP 2 LAST CDS_LIB mstr_standard
J 0
(-2925 1650);
PAINT MONO (-2925 1650);
DISPLAY INVISIBLE (-2925 1650);
FORCEPROP 1 LAST BODY_TYPE PLUMBING
J 0
(-2925 1700);
DISPLAY 1.446809 (-2925 1700);
PAINT GREEN (-2925 1700);
DISPLAY INVISIBLE (-2925 1700);
FORCEPROP 1 LAST HDL_TAP TRUE
J 0
(-2600 1525);
DISPLAY 1.446809 (-2600 1525);
PAINT GREEN (-2600 1525);
DISPLAY INVISIBLE (-2600 1525);
FORCEPROP 1 LAST PATH I47
J 0
(-2927 1650);
DISPLAY 0.872340 (-2927 1650);
PAINT GREEN (-2927 1650);
DISPLAY INVISIBLE (-2927 1650);
FORCEADD TAP..1
(-2925 1850);
FORCEPROP 3 LASTPIN (-2975 1850) SIG_NAME UPI_CPU0_CPU1_P0P0_DN<14>
J 0
(-2965 1860);
DISPLAY 0.659574 (-2965 1860);
PAINT MONO (-2965 1860);
DISPLAY INVISIBLE (-2965 1860);
FORCEPROP 1 LASTPIN (-2975 1850) BN 14
J 0
(-2987 1858);
DISPLAY 0.617021 (-2987 1858);
PAINT PINK (-2987 1858);
FORCEPROP 2 LAST CDS_LIB mstr_standard
J 0
(-2925 1850);
PAINT MONO (-2925 1850);
DISPLAY INVISIBLE (-2925 1850);
FORCEPROP 1 LAST BODY_TYPE PLUMBING
J 0
(-2925 1900);
DISPLAY 1.446809 (-2925 1900);
PAINT GREEN (-2925 1900);
DISPLAY INVISIBLE (-2925 1900);
FORCEPROP 1 LAST HDL_TAP TRUE
J 0
(-2600 1725);
DISPLAY 1.446809 (-2600 1725);
PAINT GREEN (-2600 1725);
DISPLAY INVISIBLE (-2600 1725);
FORCEPROP 1 LAST PATH I48
J 0
(-2927 1850);
DISPLAY 0.872340 (-2927 1850);
PAINT GREEN (-2927 1850);
DISPLAY INVISIBLE (-2927 1850);
FORCEADD TAP..1
(-2925 1800);
FORCEPROP 3 LASTPIN (-2975 1800) SIG_NAME UPI_CPU0_CPU1_P0P0_DN<15>
J 0
(-2965 1810);
DISPLAY 0.659574 (-2965 1810);
PAINT MONO (-2965 1810);
DISPLAY INVISIBLE (-2965 1810);
FORCEPROP 1 LASTPIN (-2975 1800) BN 15
J 0
(-2987 1808);
DISPLAY 0.617021 (-2987 1808);
PAINT PINK (-2987 1808);
FORCEPROP 2 LAST CDS_LIB mstr_standard
J 0
(-2925 1800);
PAINT MONO (-2925 1800);
DISPLAY INVISIBLE (-2925 1800);
FORCEPROP 1 LAST BODY_TYPE PLUMBING
J 0
(-2925 1850);
DISPLAY 1.446809 (-2925 1850);
PAINT GREEN (-2925 1850);
DISPLAY INVISIBLE (-2925 1850);
FORCEPROP 1 LAST HDL_TAP TRUE
J 0
(-2600 1675);
DISPLAY 1.446809 (-2600 1675);
PAINT GREEN (-2600 1675);
DISPLAY INVISIBLE (-2600 1675);
FORCEPROP 1 LAST PATH I49
J 0
(-2927 1800);
DISPLAY 0.872340 (-2927 1800);
PAINT GREEN (-2927 1800);
DISPLAY INVISIBLE (-2927 1800);
FORCEADD TAP..1
R 2
(-5250 1650);
FORCEPROP 3 LASTPIN (-5200 1650) SIG_NAME UPI_CPU1_CPU0_P0P0_DN<18>
J 0
(-5190 1660);
DISPLAY 0.659574 (-5190 1660);
PAINT MONO (-5190 1660);
DISPLAY INVISIBLE (-5190 1660);
FORCEPROP 1 LASTPIN (-5200 1650) BN 18
J 2
(-5188 1658);
DISPLAY 0.617021 (-5188 1658);
PAINT PINK (-5188 1658);
FORCEPROP 2 LAST CDS_LIB mstr_standard
J 0
(-5250 1650);
PAINT MONO (-5250 1650);
DISPLAY INVISIBLE (-5250 1650);
FORCEPROP 1 LAST BODY_TYPE PLUMBING
J 2
(-5250 1700);
DISPLAY 1.446809 (-5250 1700);
PAINT GREEN (-5250 1700);
DISPLAY INVISIBLE (-5250 1700);
FORCEPROP 1 LAST HDL_TAP TRUE
J 2
(-5575 1525);
DISPLAY 1.446809 (-5575 1525);
PAINT GREEN (-5575 1525);
DISPLAY INVISIBLE (-5575 1525);
FORCEPROP 1 LAST PATH I5
J 2
(-5248 1650);
DISPLAY 0.872340 (-5248 1650);
PAINT GREEN (-5248 1650);
DISPLAY INVISIBLE (-5248 1650);
FORCEADD TAP..1
(-2925 1900);
FORCEPROP 3 LASTPIN (-2975 1900) SIG_NAME UPI_CPU0_CPU1_P0P0_DN<13>
J 0
(-2965 1910);
DISPLAY 0.659574 (-2965 1910);
PAINT MONO (-2965 1910);
DISPLAY INVISIBLE (-2965 1910);
FORCEPROP 1 LASTPIN (-2975 1900) BN 13
J 0
(-2987 1908);
DISPLAY 0.617021 (-2987 1908);
PAINT PINK (-2987 1908);
FORCEPROP 2 LAST CDS_LIB mstr_standard
J 0
(-2925 1900);
PAINT MONO (-2925 1900);
DISPLAY INVISIBLE (-2925 1900);
FORCEPROP 1 LAST BODY_TYPE PLUMBING
J 0
(-2925 1950);
DISPLAY 1.446809 (-2925 1950);
PAINT GREEN (-2925 1950);
DISPLAY INVISIBLE (-2925 1950);
FORCEPROP 1 LAST HDL_TAP TRUE
J 0
(-2600 1775);
DISPLAY 1.446809 (-2600 1775);
PAINT GREEN (-2600 1775);
DISPLAY INVISIBLE (-2600 1775);
FORCEPROP 1 LAST PATH I50
J 0
(-2927 1900);
DISPLAY 0.872340 (-2927 1900);
PAINT GREEN (-2927 1900);
DISPLAY INVISIBLE (-2927 1900);
FORCEADD TAP..1
(-2925 2000);
FORCEPROP 3 LASTPIN (-2975 2000) SIG_NAME UPI_CPU0_CPU1_P0P0_DN<11>
J 0
(-2965 2010);
DISPLAY 0.659574 (-2965 2010);
PAINT MONO (-2965 2010);
DISPLAY INVISIBLE (-2965 2010);
FORCEPROP 1 LASTPIN (-2975 2000) BN 11
J 0
(-2987 2008);
DISPLAY 0.617021 (-2987 2008);
PAINT PINK (-2987 2008);
FORCEPROP 2 LAST CDS_LIB mstr_standard
J 0
(-2925 2000);
PAINT MONO (-2925 2000);
DISPLAY INVISIBLE (-2925 2000);
FORCEPROP 1 LAST BODY_TYPE PLUMBING
J 0
(-2925 2050);
DISPLAY 1.446809 (-2925 2050);
PAINT GREEN (-2925 2050);
DISPLAY INVISIBLE (-2925 2050);
FORCEPROP 1 LAST HDL_TAP TRUE
J 0
(-2600 1875);
DISPLAY 1.446809 (-2600 1875);
PAINT GREEN (-2600 1875);
DISPLAY INVISIBLE (-2600 1875);
FORCEPROP 1 LAST PATH I51
J 0
(-2927 2000);
DISPLAY 0.872340 (-2927 2000);
PAINT GREEN (-2927 2000);
DISPLAY INVISIBLE (-2927 2000);
FORCEADD TAP..1
(-2925 1950);
FORCEPROP 3 LASTPIN (-2975 1950) SIG_NAME UPI_CPU0_CPU1_P0P0_DN<12>
J 0
(-2965 1960);
DISPLAY 0.659574 (-2965 1960);
PAINT MONO (-2965 1960);
DISPLAY INVISIBLE (-2965 1960);
FORCEPROP 1 LASTPIN (-2975 1950) BN 12
J 0
(-2987 1958);
DISPLAY 0.617021 (-2987 1958);
PAINT PINK (-2987 1958);
FORCEPROP 2 LAST CDS_LIB mstr_standard
J 0
(-2925 1950);
PAINT MONO (-2925 1950);
DISPLAY INVISIBLE (-2925 1950);
FORCEPROP 1 LAST BODY_TYPE PLUMBING
J 0
(-2925 2000);
DISPLAY 1.446809 (-2925 2000);
PAINT GREEN (-2925 2000);
DISPLAY INVISIBLE (-2925 2000);
FORCEPROP 1 LAST HDL_TAP TRUE
J 0
(-2600 1825);
DISPLAY 1.446809 (-2600 1825);
PAINT GREEN (-2600 1825);
DISPLAY INVISIBLE (-2600 1825);
FORCEPROP 1 LAST PATH I52
J 0
(-2927 1950);
DISPLAY 0.872340 (-2927 1950);
PAINT GREEN (-2927 1950);
DISPLAY INVISIBLE (-2927 1950);
FORCEADD TAP..1
(-2925 2150);
FORCEPROP 3 LASTPIN (-2975 2150) SIG_NAME UPI_CPU0_CPU1_P0P0_DN<8>
J 0
(-2965 2160);
DISPLAY 0.659574 (-2965 2160);
PAINT MONO (-2965 2160);
DISPLAY INVISIBLE (-2965 2160);
FORCEPROP 1 LASTPIN (-2975 2150) BN 8
J 0
(-2987 2158);
DISPLAY 0.617021 (-2987 2158);
PAINT PINK (-2987 2158);
FORCEPROP 2 LAST CDS_LIB mstr_standard
J 0
(-2925 2150);
PAINT MONO (-2925 2150);
DISPLAY INVISIBLE (-2925 2150);
FORCEPROP 1 LAST BODY_TYPE PLUMBING
J 0
(-2925 2200);
DISPLAY 1.446809 (-2925 2200);
PAINT GREEN (-2925 2200);
DISPLAY INVISIBLE (-2925 2200);
FORCEPROP 1 LAST HDL_TAP TRUE
J 0
(-2600 2025);
DISPLAY 1.446809 (-2600 2025);
PAINT GREEN (-2600 2025);
DISPLAY INVISIBLE (-2600 2025);
FORCEPROP 1 LAST PATH I53
J 0
(-2927 2150);
DISPLAY 0.872340 (-2927 2150);
PAINT GREEN (-2927 2150);
DISPLAY INVISIBLE (-2927 2150);
FORCEADD TAP..1
(-2925 2100);
FORCEPROP 3 LASTPIN (-2975 2100) SIG_NAME UPI_CPU0_CPU1_P0P0_DN<9>
J 0
(-2965 2110);
DISPLAY 0.659574 (-2965 2110);
PAINT MONO (-2965 2110);
DISPLAY INVISIBLE (-2965 2110);
FORCEPROP 1 LASTPIN (-2975 2100) BN 9
J 0
(-2987 2108);
DISPLAY 0.617021 (-2987 2108);
PAINT PINK (-2987 2108);
FORCEPROP 2 LAST CDS_LIB mstr_standard
J 0
(-2925 2100);
PAINT MONO (-2925 2100);
DISPLAY INVISIBLE (-2925 2100);
FORCEPROP 1 LAST BODY_TYPE PLUMBING
J 0
(-2925 2150);
DISPLAY 1.446809 (-2925 2150);
PAINT GREEN (-2925 2150);
DISPLAY INVISIBLE (-2925 2150);
FORCEPROP 1 LAST HDL_TAP TRUE
J 0
(-2600 1975);
DISPLAY 1.446809 (-2600 1975);
PAINT GREEN (-2600 1975);
DISPLAY INVISIBLE (-2600 1975);
FORCEPROP 1 LAST PATH I54
J 0
(-2927 2100);
DISPLAY 0.872340 (-2927 2100);
PAINT GREEN (-2927 2100);
DISPLAY INVISIBLE (-2927 2100);
FORCEADD TAP..1
(-2925 2050);
FORCEPROP 3 LASTPIN (-2975 2050) SIG_NAME UPI_CPU0_CPU1_P0P0_DN<10>
J 0
(-2965 2060);
DISPLAY 0.659574 (-2965 2060);
PAINT MONO (-2965 2060);
DISPLAY INVISIBLE (-2965 2060);
FORCEPROP 1 LASTPIN (-2975 2050) BN 10
J 0
(-2987 2058);
DISPLAY 0.617021 (-2987 2058);
PAINT PINK (-2987 2058);
FORCEPROP 2 LAST CDS_LIB mstr_standard
J 0
(-2925 2050);
PAINT MONO (-2925 2050);
DISPLAY INVISIBLE (-2925 2050);
FORCEPROP 1 LAST BODY_TYPE PLUMBING
J 0
(-2925 2100);
DISPLAY 1.446809 (-2925 2100);
PAINT GREEN (-2925 2100);
DISPLAY INVISIBLE (-2925 2100);
FORCEPROP 1 LAST HDL_TAP TRUE
J 0
(-2600 1925);
DISPLAY 1.446809 (-2600 1925);
PAINT GREEN (-2600 1925);
DISPLAY INVISIBLE (-2600 1925);
FORCEPROP 1 LAST PATH I55
J 0
(-2927 2050);
DISPLAY 0.872340 (-2927 2050);
PAINT GREEN (-2927 2050);
DISPLAY INVISIBLE (-2927 2050);
FORCEADD TAP..1
(-2925 2250);
FORCEPROP 3 LASTPIN (-2975 2250) SIG_NAME UPI_CPU0_CPU1_P0P0_DN<6>
J 0
(-2965 2260);
DISPLAY 0.659574 (-2965 2260);
PAINT MONO (-2965 2260);
DISPLAY INVISIBLE (-2965 2260);
FORCEPROP 1 LASTPIN (-2975 2250) BN 6
J 0
(-2987 2258);
DISPLAY 0.617021 (-2987 2258);
PAINT PINK (-2987 2258);
FORCEPROP 2 LAST CDS_LIB mstr_standard
J 0
(-2925 2250);
PAINT MONO (-2925 2250);
DISPLAY INVISIBLE (-2925 2250);
FORCEPROP 1 LAST BODY_TYPE PLUMBING
J 0
(-2925 2300);
DISPLAY 1.446809 (-2925 2300);
PAINT GREEN (-2925 2300);
DISPLAY INVISIBLE (-2925 2300);
FORCEPROP 1 LAST HDL_TAP TRUE
J 0
(-2600 2125);
DISPLAY 1.446809 (-2600 2125);
PAINT GREEN (-2600 2125);
DISPLAY INVISIBLE (-2600 2125);
FORCEPROP 1 LAST PATH I56
J 0
(-2927 2250);
DISPLAY 0.872340 (-2927 2250);
PAINT GREEN (-2927 2250);
DISPLAY INVISIBLE (-2927 2250);
FORCEADD TAP..1
(-2925 2200);
FORCEPROP 3 LASTPIN (-2975 2200) SIG_NAME UPI_CPU0_CPU1_P0P0_DN<7>
J 0
(-2965 2210);
DISPLAY 0.659574 (-2965 2210);
PAINT MONO (-2965 2210);
DISPLAY INVISIBLE (-2965 2210);
FORCEPROP 1 LASTPIN (-2975 2200) BN 7
J 0
(-2987 2208);
DISPLAY 0.617021 (-2987 2208);
PAINT PINK (-2987 2208);
FORCEPROP 2 LAST CDS_LIB mstr_standard
J 0
(-2925 2200);
PAINT MONO (-2925 2200);
DISPLAY INVISIBLE (-2925 2200);
FORCEPROP 1 LAST BODY_TYPE PLUMBING
J 0
(-2925 2250);
DISPLAY 1.446809 (-2925 2250);
PAINT GREEN (-2925 2250);
DISPLAY INVISIBLE (-2925 2250);
FORCEPROP 1 LAST HDL_TAP TRUE
J 0
(-2600 2075);
DISPLAY 1.446809 (-2600 2075);
PAINT GREEN (-2600 2075);
DISPLAY INVISIBLE (-2600 2075);
FORCEPROP 1 LAST PATH I57
J 0
(-2927 2200);
DISPLAY 0.872340 (-2927 2200);
PAINT GREEN (-2927 2200);
DISPLAY INVISIBLE (-2927 2200);
FORCEADD TAP..1
(-2925 2300);
FORCEPROP 3 LASTPIN (-2975 2300) SIG_NAME UPI_CPU0_CPU1_P0P0_DN<5>
J 0
(-2965 2310);
DISPLAY 0.659574 (-2965 2310);
PAINT MONO (-2965 2310);
DISPLAY INVISIBLE (-2965 2310);
FORCEPROP 1 LASTPIN (-2975 2300) BN 5
J 0
(-2987 2308);
DISPLAY 0.617021 (-2987 2308);
PAINT PINK (-2987 2308);
FORCEPROP 2 LAST CDS_LIB mstr_standard
J 0
(-2925 2300);
PAINT MONO (-2925 2300);
DISPLAY INVISIBLE (-2925 2300);
FORCEPROP 1 LAST BODY_TYPE PLUMBING
J 0
(-2925 2350);
DISPLAY 1.446809 (-2925 2350);
PAINT GREEN (-2925 2350);
DISPLAY INVISIBLE (-2925 2350);
FORCEPROP 1 LAST HDL_TAP TRUE
J 0
(-2600 2175);
DISPLAY 1.446809 (-2600 2175);
PAINT GREEN (-2600 2175);
DISPLAY INVISIBLE (-2600 2175);
FORCEPROP 1 LAST PATH I58
J 0
(-2927 2300);
DISPLAY 0.872340 (-2927 2300);
PAINT GREEN (-2927 2300);
DISPLAY INVISIBLE (-2927 2300);
FORCEADD TAP..1
(-2925 2400);
FORCEPROP 3 LASTPIN (-2975 2400) SIG_NAME UPI_CPU0_CPU1_P0P0_DN<3>
J 0
(-2965 2410);
DISPLAY 0.659574 (-2965 2410);
PAINT MONO (-2965 2410);
DISPLAY INVISIBLE (-2965 2410);
FORCEPROP 1 LASTPIN (-2975 2400) BN 3
J 0
(-2987 2408);
DISPLAY 0.617021 (-2987 2408);
PAINT PINK (-2987 2408);
FORCEPROP 2 LAST CDS_LIB mstr_standard
J 0
(-2925 2400);
PAINT MONO (-2925 2400);
DISPLAY INVISIBLE (-2925 2400);
FORCEPROP 1 LAST BODY_TYPE PLUMBING
J 0
(-2925 2450);
DISPLAY 1.446809 (-2925 2450);
PAINT GREEN (-2925 2450);
DISPLAY INVISIBLE (-2925 2450);
FORCEPROP 1 LAST HDL_TAP TRUE
J 0
(-2600 2275);
DISPLAY 1.446809 (-2600 2275);
PAINT GREEN (-2600 2275);
DISPLAY INVISIBLE (-2600 2275);
FORCEPROP 1 LAST PATH I59
J 0
(-2927 2400);
DISPLAY 0.872340 (-2927 2400);
PAINT GREEN (-2927 2400);
DISPLAY INVISIBLE (-2927 2400);
FORCEADD TAP..1
R 2
(-5250 1750);
FORCEPROP 3 LASTPIN (-5200 1750) SIG_NAME UPI_CPU1_CPU0_P0P0_DN<16>
J 0
(-5190 1760);
DISPLAY 0.659574 (-5190 1760);
PAINT MONO (-5190 1760);
DISPLAY INVISIBLE (-5190 1760);
FORCEPROP 1 LASTPIN (-5200 1750) BN 16
J 2
(-5188 1758);
DISPLAY 0.617021 (-5188 1758);
PAINT PINK (-5188 1758);
FORCEPROP 2 LAST CDS_LIB mstr_standard
J 0
(-5250 1750);
PAINT MONO (-5250 1750);
DISPLAY INVISIBLE (-5250 1750);
FORCEPROP 1 LAST BODY_TYPE PLUMBING
J 2
(-5250 1800);
DISPLAY 1.446809 (-5250 1800);
PAINT GREEN (-5250 1800);
DISPLAY INVISIBLE (-5250 1800);
FORCEPROP 1 LAST HDL_TAP TRUE
J 2
(-5575 1625);
DISPLAY 1.446809 (-5575 1625);
PAINT GREEN (-5575 1625);
DISPLAY INVISIBLE (-5575 1625);
FORCEPROP 1 LAST PATH I6
J 2
(-5248 1750);
DISPLAY 0.872340 (-5248 1750);
PAINT GREEN (-5248 1750);
DISPLAY INVISIBLE (-5248 1750);
FORCEADD TAP..1
(-2925 2350);
FORCEPROP 3 LASTPIN (-2975 2350) SIG_NAME UPI_CPU0_CPU1_P0P0_DN<4>
J 0
(-2965 2360);
DISPLAY 0.659574 (-2965 2360);
PAINT MONO (-2965 2360);
DISPLAY INVISIBLE (-2965 2360);
FORCEPROP 1 LASTPIN (-2975 2350) BN 4
J 0
(-2987 2358);
DISPLAY 0.617021 (-2987 2358);
PAINT PINK (-2987 2358);
FORCEPROP 2 LAST CDS_LIB mstr_standard
J 0
(-2925 2350);
PAINT MONO (-2925 2350);
DISPLAY INVISIBLE (-2925 2350);
FORCEPROP 1 LAST BODY_TYPE PLUMBING
J 0
(-2925 2400);
DISPLAY 1.446809 (-2925 2400);
PAINT GREEN (-2925 2400);
DISPLAY INVISIBLE (-2925 2400);
FORCEPROP 1 LAST HDL_TAP TRUE
J 0
(-2600 2225);
DISPLAY 1.446809 (-2600 2225);
PAINT GREEN (-2600 2225);
DISPLAY INVISIBLE (-2600 2225);
FORCEPROP 1 LAST PATH I60
J 0
(-2927 2350);
DISPLAY 0.872340 (-2927 2350);
PAINT GREEN (-2927 2350);
DISPLAY INVISIBLE (-2927 2350);
FORCEADD TAP..1
(-2925 2450);
FORCEPROP 3 LASTPIN (-2975 2450) SIG_NAME UPI_CPU0_CPU1_P0P0_DN<2>
J 0
(-2965 2460);
DISPLAY 0.659574 (-2965 2460);
PAINT MONO (-2965 2460);
DISPLAY INVISIBLE (-2965 2460);
FORCEPROP 1 LASTPIN (-2975 2450) BN 2
J 0
(-2987 2458);
DISPLAY 0.617021 (-2987 2458);
PAINT PINK (-2987 2458);
FORCEPROP 2 LAST CDS_LIB mstr_standard
J 0
(-2925 2450);
PAINT MONO (-2925 2450);
DISPLAY INVISIBLE (-2925 2450);
FORCEPROP 1 LAST BODY_TYPE PLUMBING
J 0
(-2925 2500);
DISPLAY 1.446809 (-2925 2500);
PAINT GREEN (-2925 2500);
DISPLAY INVISIBLE (-2925 2500);
FORCEPROP 1 LAST HDL_TAP TRUE
J 0
(-2600 2325);
DISPLAY 1.446809 (-2600 2325);
PAINT GREEN (-2600 2325);
DISPLAY INVISIBLE (-2600 2325);
FORCEPROP 1 LAST PATH I61
J 0
(-2927 2450);
DISPLAY 0.872340 (-2927 2450);
PAINT GREEN (-2927 2450);
DISPLAY INVISIBLE (-2927 2450);
FORCEADD TAP..1
(-2925 2500);
FORCEPROP 3 LASTPIN (-2975 2500) SIG_NAME UPI_CPU0_CPU1_P0P0_DN<1>
J 0
(-2965 2510);
DISPLAY 0.659574 (-2965 2510);
PAINT MONO (-2965 2510);
DISPLAY INVISIBLE (-2965 2510);
FORCEPROP 1 LASTPIN (-2975 2500) BN 1
J 0
(-2987 2508);
DISPLAY 0.617021 (-2987 2508);
PAINT PINK (-2987 2508);
FORCEPROP 2 LAST CDS_LIB mstr_standard
J 0
(-2925 2500);
PAINT MONO (-2925 2500);
DISPLAY INVISIBLE (-2925 2500);
FORCEPROP 1 LAST BODY_TYPE PLUMBING
J 0
(-2925 2550);
DISPLAY 1.446809 (-2925 2550);
PAINT GREEN (-2925 2550);
DISPLAY INVISIBLE (-2925 2550);
FORCEPROP 1 LAST HDL_TAP TRUE
J 0
(-2600 2375);
DISPLAY 1.446809 (-2600 2375);
PAINT GREEN (-2600 2375);
DISPLAY INVISIBLE (-2600 2375);
FORCEPROP 1 LAST PATH I62
J 0
(-2927 2500);
DISPLAY 0.872340 (-2927 2500);
PAINT GREEN (-2927 2500);
DISPLAY INVISIBLE (-2927 2500);
FORCEADD TAP..1
(-2925 2550);
FORCEPROP 3 LASTPIN (-2975 2550) SIG_NAME UPI_CPU0_CPU1_P0P0_DN<0>
J 0
(-2965 2560);
DISPLAY 0.659574 (-2965 2560);
PAINT MONO (-2965 2560);
DISPLAY INVISIBLE (-2965 2560);
FORCEPROP 1 LASTPIN (-2975 2550) BN 0
J 0
(-2987 2558);
DISPLAY 0.617021 (-2987 2558);
PAINT PINK (-2987 2558);
FORCEPROP 2 LAST CDS_LIB mstr_standard
J 0
(-2925 2550);
PAINT MONO (-2925 2550);
DISPLAY INVISIBLE (-2925 2550);
FORCEPROP 1 LAST BODY_TYPE PLUMBING
J 0
(-2925 2600);
DISPLAY 1.446809 (-2925 2600);
PAINT GREEN (-2925 2600);
DISPLAY INVISIBLE (-2925 2600);
FORCEPROP 1 LAST HDL_TAP TRUE
J 0
(-2600 2425);
DISPLAY 1.446809 (-2600 2425);
PAINT GREEN (-2600 2425);
DISPLAY INVISIBLE (-2600 2425);
FORCEPROP 1 LAST PATH I63
J 0
(-2927 2550);
DISPLAY 0.872340 (-2927 2550);
PAINT GREEN (-2927 2550);
DISPLAY INVISIBLE (-2927 2550);
FORCEADD TAP..1
(-2925 2650);
FORCEPROP 3 LASTPIN (-2975 2650) SIG_NAME UPI_CPU0_CPU1_P0P0_DP<19>
J 0
(-2965 2660);
DISPLAY 0.659574 (-2965 2660);
PAINT MONO (-2965 2660);
DISPLAY INVISIBLE (-2965 2660);
FORCEPROP 1 LASTPIN (-2975 2650) BN 19
J 0
(-2987 2658);
DISPLAY 0.617021 (-2987 2658);
PAINT PINK (-2987 2658);
FORCEPROP 2 LAST CDS_LIB mstr_standard
J 0
(-2925 2650);
PAINT MONO (-2925 2650);
DISPLAY INVISIBLE (-2925 2650);
FORCEPROP 1 LAST BODY_TYPE PLUMBING
J 0
(-2925 2700);
DISPLAY 1.446809 (-2925 2700);
PAINT GREEN (-2925 2700);
DISPLAY INVISIBLE (-2925 2700);
FORCEPROP 1 LAST HDL_TAP TRUE
J 0
(-2600 2525);
DISPLAY 1.446809 (-2600 2525);
PAINT GREEN (-2600 2525);
DISPLAY INVISIBLE (-2600 2525);
FORCEPROP 1 LAST PATH I64
J 0
(-2927 2650);
DISPLAY 0.872340 (-2927 2650);
PAINT GREEN (-2927 2650);
DISPLAY INVISIBLE (-2927 2650);
FORCEADD TAP..1
(-2925 2750);
FORCEPROP 3 LASTPIN (-2975 2750) SIG_NAME UPI_CPU0_CPU1_P0P0_DP<17>
J 0
(-2965 2760);
DISPLAY 0.659574 (-2965 2760);
PAINT MONO (-2965 2760);
DISPLAY INVISIBLE (-2965 2760);
FORCEPROP 1 LASTPIN (-2975 2750) BN 17
J 0
(-2987 2758);
DISPLAY 0.617021 (-2987 2758);
PAINT PINK (-2987 2758);
FORCEPROP 2 LAST CDS_LIB mstr_standard
J 0
(-2925 2750);
PAINT MONO (-2925 2750);
DISPLAY INVISIBLE (-2925 2750);
FORCEPROP 1 LAST BODY_TYPE PLUMBING
J 0
(-2925 2800);
DISPLAY 1.446809 (-2925 2800);
PAINT GREEN (-2925 2800);
DISPLAY INVISIBLE (-2925 2800);
FORCEPROP 1 LAST HDL_TAP TRUE
J 0
(-2600 2625);
DISPLAY 1.446809 (-2600 2625);
PAINT GREEN (-2600 2625);
DISPLAY INVISIBLE (-2600 2625);
FORCEPROP 1 LAST PATH I65
J 0
(-2927 2750);
DISPLAY 0.872340 (-2927 2750);
PAINT GREEN (-2927 2750);
DISPLAY INVISIBLE (-2927 2750);
FORCEADD TAP..1
(-2925 2700);
FORCEPROP 3 LASTPIN (-2975 2700) SIG_NAME UPI_CPU0_CPU1_P0P0_DP<18>
J 0
(-2965 2710);
DISPLAY 0.659574 (-2965 2710);
PAINT MONO (-2965 2710);
DISPLAY INVISIBLE (-2965 2710);
FORCEPROP 1 LASTPIN (-2975 2700) BN 18
J 0
(-2987 2708);
DISPLAY 0.617021 (-2987 2708);
PAINT PINK (-2987 2708);
FORCEPROP 2 LAST CDS_LIB mstr_standard
J 0
(-2925 2700);
PAINT MONO (-2925 2700);
DISPLAY INVISIBLE (-2925 2700);
FORCEPROP 1 LAST BODY_TYPE PLUMBING
J 0
(-2925 2750);
DISPLAY 1.446809 (-2925 2750);
PAINT GREEN (-2925 2750);
DISPLAY INVISIBLE (-2925 2750);
FORCEPROP 1 LAST HDL_TAP TRUE
J 0
(-2600 2575);
DISPLAY 1.446809 (-2600 2575);
PAINT GREEN (-2600 2575);
DISPLAY INVISIBLE (-2600 2575);
FORCEPROP 1 LAST PATH I66
J 0
(-2927 2700);
DISPLAY 0.872340 (-2927 2700);
PAINT GREEN (-2927 2700);
DISPLAY INVISIBLE (-2927 2700);
FORCEADD TAP..1
(-2925 2800);
FORCEPROP 3 LASTPIN (-2975 2800) SIG_NAME UPI_CPU0_CPU1_P0P0_DP<16>
J 0
(-2965 2810);
DISPLAY 0.659574 (-2965 2810);
PAINT MONO (-2965 2810);
DISPLAY INVISIBLE (-2965 2810);
FORCEPROP 1 LASTPIN (-2975 2800) BN 16
J 0
(-2987 2808);
DISPLAY 0.617021 (-2987 2808);
PAINT PINK (-2987 2808);
FORCEPROP 2 LAST CDS_LIB mstr_standard
J 0
(-2925 2800);
PAINT MONO (-2925 2800);
DISPLAY INVISIBLE (-2925 2800);
FORCEPROP 1 LAST BODY_TYPE PLUMBING
J 0
(-2925 2850);
DISPLAY 1.446809 (-2925 2850);
PAINT GREEN (-2925 2850);
DISPLAY INVISIBLE (-2925 2850);
FORCEPROP 1 LAST HDL_TAP TRUE
J 0
(-2600 2675);
DISPLAY 1.446809 (-2600 2675);
PAINT GREEN (-2600 2675);
DISPLAY INVISIBLE (-2600 2675);
FORCEPROP 1 LAST PATH I67
J 0
(-2927 2800);
DISPLAY 0.872340 (-2927 2800);
PAINT GREEN (-2927 2800);
DISPLAY INVISIBLE (-2927 2800);
FORCEADD TAP..1
(-2925 2850);
FORCEPROP 3 LASTPIN (-2975 2850) SIG_NAME UPI_CPU0_CPU1_P0P0_DP<15>
J 0
(-2965 2860);
DISPLAY 0.659574 (-2965 2860);
PAINT MONO (-2965 2860);
DISPLAY INVISIBLE (-2965 2860);
FORCEPROP 1 LASTPIN (-2975 2850) BN 15
J 0
(-2987 2858);
DISPLAY 0.617021 (-2987 2858);
PAINT PINK (-2987 2858);
FORCEPROP 2 LAST CDS_LIB mstr_standard
J 0
(-2925 2850);
PAINT MONO (-2925 2850);
DISPLAY INVISIBLE (-2925 2850);
FORCEPROP 1 LAST BODY_TYPE PLUMBING
J 0
(-2925 2900);
DISPLAY 1.446809 (-2925 2900);
PAINT GREEN (-2925 2900);
DISPLAY INVISIBLE (-2925 2900);
FORCEPROP 1 LAST HDL_TAP TRUE
J 0
(-2600 2725);
DISPLAY 1.446809 (-2600 2725);
PAINT GREEN (-2600 2725);
DISPLAY INVISIBLE (-2600 2725);
FORCEPROP 1 LAST PATH I68
J 0
(-2927 2850);
DISPLAY 0.872340 (-2927 2850);
PAINT GREEN (-2927 2850);
DISPLAY INVISIBLE (-2927 2850);
FORCEADD TAP..1
(-2925 2900);
FORCEPROP 3 LASTPIN (-2975 2900) SIG_NAME UPI_CPU0_CPU1_P0P0_DP<14>
J 0
(-2965 2910);
DISPLAY 0.659574 (-2965 2910);
PAINT MONO (-2965 2910);
DISPLAY INVISIBLE (-2965 2910);
FORCEPROP 1 LASTPIN (-2975 2900) BN 14
J 0
(-2987 2908);
DISPLAY 0.617021 (-2987 2908);
PAINT PINK (-2987 2908);
FORCEPROP 2 LAST CDS_LIB mstr_standard
J 0
(-2925 2900);
PAINT MONO (-2925 2900);
DISPLAY INVISIBLE (-2925 2900);
FORCEPROP 1 LAST BODY_TYPE PLUMBING
J 0
(-2925 2950);
DISPLAY 1.446809 (-2925 2950);
PAINT GREEN (-2925 2950);
DISPLAY INVISIBLE (-2925 2950);
FORCEPROP 1 LAST HDL_TAP TRUE
J 0
(-2600 2775);
DISPLAY 1.446809 (-2600 2775);
PAINT GREEN (-2600 2775);
DISPLAY INVISIBLE (-2600 2775);
FORCEPROP 1 LAST PATH I69
J 0
(-2927 2900);
DISPLAY 0.872340 (-2927 2900);
PAINT GREEN (-2927 2900);
DISPLAY INVISIBLE (-2927 2900);
FORCEADD TAP..1
R 2
(-5250 1800);
FORCEPROP 3 LASTPIN (-5200 1800) SIG_NAME UPI_CPU1_CPU0_P0P0_DN<15>
J 0
(-5190 1810);
DISPLAY 0.659574 (-5190 1810);
PAINT MONO (-5190 1810);
DISPLAY INVISIBLE (-5190 1810);
FORCEPROP 1 LASTPIN (-5200 1800) BN 15
J 2
(-5188 1808);
DISPLAY 0.617021 (-5188 1808);
PAINT PINK (-5188 1808);
FORCEPROP 2 LAST CDS_LIB mstr_standard
J 0
(-5250 1800);
PAINT MONO (-5250 1800);
DISPLAY INVISIBLE (-5250 1800);
FORCEPROP 1 LAST BODY_TYPE PLUMBING
J 2
(-5250 1850);
DISPLAY 1.446809 (-5250 1850);
PAINT GREEN (-5250 1850);
DISPLAY INVISIBLE (-5250 1850);
FORCEPROP 1 LAST HDL_TAP TRUE
J 2
(-5575 1675);
DISPLAY 1.446809 (-5575 1675);
PAINT GREEN (-5575 1675);
DISPLAY INVISIBLE (-5575 1675);
FORCEPROP 1 LAST PATH I7
J 2
(-5248 1800);
DISPLAY 0.872340 (-5248 1800);
PAINT GREEN (-5248 1800);
DISPLAY INVISIBLE (-5248 1800);
FORCEADD TAP..1
(-2925 3000);
FORCEPROP 3 LASTPIN (-2975 3000) SIG_NAME UPI_CPU0_CPU1_P0P0_DP<12>
J 0
(-2965 3010);
DISPLAY 0.659574 (-2965 3010);
PAINT MONO (-2965 3010);
DISPLAY INVISIBLE (-2965 3010);
FORCEPROP 1 LASTPIN (-2975 3000) BN 12
J 0
(-2987 3008);
DISPLAY 0.617021 (-2987 3008);
PAINT PINK (-2987 3008);
FORCEPROP 2 LAST CDS_LIB mstr_standard
J 0
(-2925 3000);
PAINT MONO (-2925 3000);
DISPLAY INVISIBLE (-2925 3000);
FORCEPROP 1 LAST BODY_TYPE PLUMBING
J 0
(-2925 3050);
DISPLAY 1.446809 (-2925 3050);
PAINT GREEN (-2925 3050);
DISPLAY INVISIBLE (-2925 3050);
FORCEPROP 1 LAST HDL_TAP TRUE
J 0
(-2600 2875);
DISPLAY 1.446809 (-2600 2875);
PAINT GREEN (-2600 2875);
DISPLAY INVISIBLE (-2600 2875);
FORCEPROP 1 LAST PATH I70
J 0
(-2927 3000);
DISPLAY 0.872340 (-2927 3000);
PAINT GREEN (-2927 3000);
DISPLAY INVISIBLE (-2927 3000);
FORCEADD TAP..1
(-2925 2950);
FORCEPROP 3 LASTPIN (-2975 2950) SIG_NAME UPI_CPU0_CPU1_P0P0_DP<13>
J 0
(-2965 2960);
DISPLAY 0.659574 (-2965 2960);
PAINT MONO (-2965 2960);
DISPLAY INVISIBLE (-2965 2960);
FORCEPROP 1 LASTPIN (-2975 2950) BN 13
J 0
(-2987 2958);
DISPLAY 0.617021 (-2987 2958);
PAINT PINK (-2987 2958);
FORCEPROP 2 LAST CDS_LIB mstr_standard
J 0
(-2925 2950);
PAINT MONO (-2925 2950);
DISPLAY INVISIBLE (-2925 2950);
FORCEPROP 1 LAST BODY_TYPE PLUMBING
J 0
(-2925 3000);
DISPLAY 1.446809 (-2925 3000);
PAINT GREEN (-2925 3000);
DISPLAY INVISIBLE (-2925 3000);
FORCEPROP 1 LAST HDL_TAP TRUE
J 0
(-2600 2825);
DISPLAY 1.446809 (-2600 2825);
PAINT GREEN (-2600 2825);
DISPLAY INVISIBLE (-2600 2825);
FORCEPROP 1 LAST PATH I71
J 0
(-2927 2950);
DISPLAY 0.872340 (-2927 2950);
PAINT GREEN (-2927 2950);
DISPLAY INVISIBLE (-2927 2950);
FORCEADD TAP..1
(-2925 3050);
FORCEPROP 3 LASTPIN (-2975 3050) SIG_NAME UPI_CPU0_CPU1_P0P0_DP<11>
J 0
(-2965 3060);
DISPLAY 0.659574 (-2965 3060);
PAINT MONO (-2965 3060);
DISPLAY INVISIBLE (-2965 3060);
FORCEPROP 1 LASTPIN (-2975 3050) BN 11
J 0
(-2987 3058);
DISPLAY 0.617021 (-2987 3058);
PAINT PINK (-2987 3058);
FORCEPROP 2 LAST CDS_LIB mstr_standard
J 0
(-2925 3050);
PAINT MONO (-2925 3050);
DISPLAY INVISIBLE (-2925 3050);
FORCEPROP 1 LAST BODY_TYPE PLUMBING
J 0
(-2925 3100);
DISPLAY 1.446809 (-2925 3100);
PAINT GREEN (-2925 3100);
DISPLAY INVISIBLE (-2925 3100);
FORCEPROP 1 LAST HDL_TAP TRUE
J 0
(-2600 2925);
DISPLAY 1.446809 (-2600 2925);
PAINT GREEN (-2600 2925);
DISPLAY INVISIBLE (-2600 2925);
FORCEPROP 1 LAST PATH I72
J 0
(-2927 3050);
DISPLAY 0.872340 (-2927 3050);
PAINT GREEN (-2927 3050);
DISPLAY INVISIBLE (-2927 3050);
FORCEADD TAP..1
(-2925 3100);
FORCEPROP 3 LASTPIN (-2975 3100) SIG_NAME UPI_CPU0_CPU1_P0P0_DP<10>
J 0
(-2965 3110);
DISPLAY 0.659574 (-2965 3110);
PAINT MONO (-2965 3110);
DISPLAY INVISIBLE (-2965 3110);
FORCEPROP 1 LASTPIN (-2975 3100) BN 10
J 0
(-2987 3108);
DISPLAY 0.617021 (-2987 3108);
PAINT PINK (-2987 3108);
FORCEPROP 2 LAST CDS_LIB mstr_standard
J 0
(-2925 3100);
PAINT MONO (-2925 3100);
DISPLAY INVISIBLE (-2925 3100);
FORCEPROP 1 LAST BODY_TYPE PLUMBING
J 0
(-2925 3150);
DISPLAY 1.446809 (-2925 3150);
PAINT GREEN (-2925 3150);
DISPLAY INVISIBLE (-2925 3150);
FORCEPROP 1 LAST HDL_TAP TRUE
J 0
(-2600 2975);
DISPLAY 1.446809 (-2600 2975);
PAINT GREEN (-2600 2975);
DISPLAY INVISIBLE (-2600 2975);
FORCEPROP 1 LAST PATH I73
J 0
(-2927 3100);
DISPLAY 0.872340 (-2927 3100);
PAINT GREEN (-2927 3100);
DISPLAY INVISIBLE (-2927 3100);
FORCEADD TAP..1
(-2925 3150);
FORCEPROP 3 LASTPIN (-2975 3150) SIG_NAME UPI_CPU0_CPU1_P0P0_DP<9>
J 0
(-2965 3160);
DISPLAY 0.659574 (-2965 3160);
PAINT MONO (-2965 3160);
DISPLAY INVISIBLE (-2965 3160);
FORCEPROP 1 LASTPIN (-2975 3150) BN 9
J 0
(-2987 3158);
DISPLAY 0.617021 (-2987 3158);
PAINT PINK (-2987 3158);
FORCEPROP 2 LAST CDS_LIB mstr_standard
J 0
(-2925 3150);
PAINT MONO (-2925 3150);
DISPLAY INVISIBLE (-2925 3150);
FORCEPROP 1 LAST BODY_TYPE PLUMBING
J 0
(-2925 3200);
DISPLAY 1.446809 (-2925 3200);
PAINT GREEN (-2925 3200);
DISPLAY INVISIBLE (-2925 3200);
FORCEPROP 1 LAST HDL_TAP TRUE
J 0
(-2600 3025);
DISPLAY 1.446809 (-2600 3025);
PAINT GREEN (-2600 3025);
DISPLAY INVISIBLE (-2600 3025);
FORCEPROP 1 LAST PATH I74
J 0
(-2927 3150);
DISPLAY 0.872340 (-2927 3150);
PAINT GREEN (-2927 3150);
DISPLAY INVISIBLE (-2927 3150);
FORCEADD TAP..1
(-2925 3250);
FORCEPROP 3 LASTPIN (-2975 3250) SIG_NAME UPI_CPU0_CPU1_P0P0_DP<7>
J 0
(-2965 3260);
DISPLAY 0.659574 (-2965 3260);
PAINT MONO (-2965 3260);
DISPLAY INVISIBLE (-2965 3260);
FORCEPROP 1 LASTPIN (-2975 3250) BN 7
J 0
(-2987 3258);
DISPLAY 0.617021 (-2987 3258);
PAINT PINK (-2987 3258);
FORCEPROP 2 LAST CDS_LIB mstr_standard
J 0
(-2925 3250);
PAINT MONO (-2925 3250);
DISPLAY INVISIBLE (-2925 3250);
FORCEPROP 1 LAST BODY_TYPE PLUMBING
J 0
(-2925 3300);
DISPLAY 1.446809 (-2925 3300);
PAINT GREEN (-2925 3300);
DISPLAY INVISIBLE (-2925 3300);
FORCEPROP 1 LAST HDL_TAP TRUE
J 0
(-2600 3125);
DISPLAY 1.446809 (-2600 3125);
PAINT GREEN (-2600 3125);
DISPLAY INVISIBLE (-2600 3125);
FORCEPROP 1 LAST PATH I75
J 0
(-2927 3250);
DISPLAY 0.872340 (-2927 3250);
PAINT GREEN (-2927 3250);
DISPLAY INVISIBLE (-2927 3250);
FORCEADD TAP..1
(-2925 3300);
FORCEPROP 3 LASTPIN (-2975 3300) SIG_NAME UPI_CPU0_CPU1_P0P0_DP<6>
J 0
(-2965 3310);
DISPLAY 0.659574 (-2965 3310);
PAINT MONO (-2965 3310);
DISPLAY INVISIBLE (-2965 3310);
FORCEPROP 1 LASTPIN (-2975 3300) BN 6
J 0
(-2987 3308);
DISPLAY 0.617021 (-2987 3308);
PAINT PINK (-2987 3308);
FORCEPROP 2 LAST CDS_LIB mstr_standard
J 0
(-2925 3300);
PAINT MONO (-2925 3300);
DISPLAY INVISIBLE (-2925 3300);
FORCEPROP 1 LAST BODY_TYPE PLUMBING
J 0
(-2925 3350);
DISPLAY 1.446809 (-2925 3350);
PAINT GREEN (-2925 3350);
DISPLAY INVISIBLE (-2925 3350);
FORCEPROP 1 LAST HDL_TAP TRUE
J 0
(-2600 3175);
DISPLAY 1.446809 (-2600 3175);
PAINT GREEN (-2600 3175);
DISPLAY INVISIBLE (-2600 3175);
FORCEPROP 1 LAST PATH I76
J 0
(-2927 3300);
DISPLAY 0.872340 (-2927 3300);
PAINT GREEN (-2927 3300);
DISPLAY INVISIBLE (-2927 3300);
FORCEADD TAP..1
(-2925 3200);
FORCEPROP 3 LASTPIN (-2975 3200) SIG_NAME UPI_CPU0_CPU1_P0P0_DP<8>
J 0
(-2965 3210);
DISPLAY 0.659574 (-2965 3210);
PAINT MONO (-2965 3210);
DISPLAY INVISIBLE (-2965 3210);
FORCEPROP 1 LASTPIN (-2975 3200) BN 8
J 0
(-2987 3208);
DISPLAY 0.617021 (-2987 3208);
PAINT PINK (-2987 3208);
FORCEPROP 2 LAST CDS_LIB mstr_standard
J 0
(-2925 3200);
PAINT MONO (-2925 3200);
DISPLAY INVISIBLE (-2925 3200);
FORCEPROP 1 LAST BODY_TYPE PLUMBING
J 0
(-2925 3250);
DISPLAY 1.446809 (-2925 3250);
PAINT GREEN (-2925 3250);
DISPLAY INVISIBLE (-2925 3250);
FORCEPROP 1 LAST HDL_TAP TRUE
J 0
(-2600 3075);
DISPLAY 1.446809 (-2600 3075);
PAINT GREEN (-2600 3075);
DISPLAY INVISIBLE (-2600 3075);
FORCEPROP 1 LAST PATH I77
J 0
(-2927 3200);
DISPLAY 0.872340 (-2927 3200);
PAINT GREEN (-2927 3200);
DISPLAY INVISIBLE (-2927 3200);
FORCEADD TAP..1
(-2925 3350);
FORCEPROP 3 LASTPIN (-2975 3350) SIG_NAME UPI_CPU0_CPU1_P0P0_DP<5>
J 0
(-2965 3360);
DISPLAY 0.659574 (-2965 3360);
PAINT MONO (-2965 3360);
DISPLAY INVISIBLE (-2965 3360);
FORCEPROP 1 LASTPIN (-2975 3350) BN 5
J 0
(-2987 3358);
DISPLAY 0.617021 (-2987 3358);
PAINT PINK (-2987 3358);
FORCEPROP 2 LAST CDS_LIB mstr_standard
J 0
(-2925 3350);
PAINT MONO (-2925 3350);
DISPLAY INVISIBLE (-2925 3350);
FORCEPROP 1 LAST BODY_TYPE PLUMBING
J 0
(-2925 3400);
DISPLAY 1.446809 (-2925 3400);
PAINT GREEN (-2925 3400);
DISPLAY INVISIBLE (-2925 3400);
FORCEPROP 1 LAST HDL_TAP TRUE
J 0
(-2600 3225);
DISPLAY 1.446809 (-2600 3225);
PAINT GREEN (-2600 3225);
DISPLAY INVISIBLE (-2600 3225);
FORCEPROP 1 LAST PATH I78
J 0
(-2927 3350);
DISPLAY 0.872340 (-2927 3350);
PAINT GREEN (-2927 3350);
DISPLAY INVISIBLE (-2927 3350);
FORCEADD TAP..1
(-2925 3400);
FORCEPROP 3 LASTPIN (-2975 3400) SIG_NAME UPI_CPU0_CPU1_P0P0_DP<4>
J 0
(-2965 3410);
DISPLAY 0.659574 (-2965 3410);
PAINT MONO (-2965 3410);
DISPLAY INVISIBLE (-2965 3410);
FORCEPROP 1 LASTPIN (-2975 3400) BN 4
J 0
(-2987 3408);
DISPLAY 0.617021 (-2987 3408);
PAINT PINK (-2987 3408);
FORCEPROP 2 LAST CDS_LIB mstr_standard
J 0
(-2925 3400);
PAINT MONO (-2925 3400);
DISPLAY INVISIBLE (-2925 3400);
FORCEPROP 1 LAST BODY_TYPE PLUMBING
J 0
(-2925 3450);
DISPLAY 1.446809 (-2925 3450);
PAINT GREEN (-2925 3450);
DISPLAY INVISIBLE (-2925 3450);
FORCEPROP 1 LAST HDL_TAP TRUE
J 0
(-2600 3275);
DISPLAY 1.446809 (-2600 3275);
PAINT GREEN (-2600 3275);
DISPLAY INVISIBLE (-2600 3275);
FORCEPROP 1 LAST PATH I79
J 0
(-2927 3400);
DISPLAY 0.872340 (-2927 3400);
PAINT GREEN (-2927 3400);
DISPLAY INVISIBLE (-2927 3400);
FORCEADD TAP..1
R 2
(-5250 1850);
FORCEPROP 3 LASTPIN (-5200 1850) SIG_NAME UPI_CPU1_CPU0_P0P0_DN<14>
J 0
(-5190 1860);
DISPLAY 0.659574 (-5190 1860);
PAINT MONO (-5190 1860);
DISPLAY INVISIBLE (-5190 1860);
FORCEPROP 1 LASTPIN (-5200 1850) BN 14
J 2
(-5188 1858);
DISPLAY 0.617021 (-5188 1858);
PAINT PINK (-5188 1858);
FORCEPROP 2 LAST CDS_LIB mstr_standard
J 0
(-5250 1850);
PAINT MONO (-5250 1850);
DISPLAY INVISIBLE (-5250 1850);
FORCEPROP 1 LAST BODY_TYPE PLUMBING
J 2
(-5250 1900);
DISPLAY 1.446809 (-5250 1900);
PAINT GREEN (-5250 1900);
DISPLAY INVISIBLE (-5250 1900);
FORCEPROP 1 LAST HDL_TAP TRUE
J 2
(-5575 1725);
DISPLAY 1.446809 (-5575 1725);
PAINT GREEN (-5575 1725);
DISPLAY INVISIBLE (-5575 1725);
FORCEPROP 1 LAST PATH I8
J 2
(-5248 1850);
DISPLAY 0.872340 (-5248 1850);
PAINT GREEN (-5248 1850);
DISPLAY INVISIBLE (-5248 1850);
FORCEADD TAP..1
(-2925 3550);
FORCEPROP 3 LASTPIN (-2975 3550) SIG_NAME UPI_CPU0_CPU1_P0P0_DP<1>
J 0
(-2965 3560);
DISPLAY 0.659574 (-2965 3560);
PAINT MONO (-2965 3560);
DISPLAY INVISIBLE (-2965 3560);
FORCEPROP 1 LASTPIN (-2975 3550) BN 1
J 0
(-2987 3558);
DISPLAY 0.617021 (-2987 3558);
PAINT PINK (-2987 3558);
FORCEPROP 2 LAST CDS_LIB mstr_standard
J 0
(-2925 3550);
PAINT MONO (-2925 3550);
DISPLAY INVISIBLE (-2925 3550);
FORCEPROP 1 LAST BODY_TYPE PLUMBING
J 0
(-2925 3600);
DISPLAY 1.446809 (-2925 3600);
PAINT GREEN (-2925 3600);
DISPLAY INVISIBLE (-2925 3600);
FORCEPROP 1 LAST HDL_TAP TRUE
J 0
(-2600 3425);
DISPLAY 1.446809 (-2600 3425);
PAINT GREEN (-2600 3425);
DISPLAY INVISIBLE (-2600 3425);
FORCEPROP 1 LAST PATH I80
J 0
(-2927 3550);
DISPLAY 0.872340 (-2927 3550);
PAINT GREEN (-2927 3550);
DISPLAY INVISIBLE (-2927 3550);
FORCEADD TAP..1
(-2925 3500);
FORCEPROP 3 LASTPIN (-2975 3500) SIG_NAME UPI_CPU0_CPU1_P0P0_DP<2>
J 0
(-2965 3510);
DISPLAY 0.659574 (-2965 3510);
PAINT MONO (-2965 3510);
DISPLAY INVISIBLE (-2965 3510);
FORCEPROP 1 LASTPIN (-2975 3500) BN 2
J 0
(-2987 3508);
DISPLAY 0.617021 (-2987 3508);
PAINT PINK (-2987 3508);
FORCEPROP 2 LAST CDS_LIB mstr_standard
J 0
(-2925 3500);
PAINT MONO (-2925 3500);
DISPLAY INVISIBLE (-2925 3500);
FORCEPROP 1 LAST BODY_TYPE PLUMBING
J 0
(-2925 3550);
DISPLAY 1.446809 (-2925 3550);
PAINT GREEN (-2925 3550);
DISPLAY INVISIBLE (-2925 3550);
FORCEPROP 1 LAST HDL_TAP TRUE
J 0
(-2600 3375);
DISPLAY 1.446809 (-2600 3375);
PAINT GREEN (-2600 3375);
DISPLAY INVISIBLE (-2600 3375);
FORCEPROP 1 LAST PATH I81
J 0
(-2927 3500);
DISPLAY 0.872340 (-2927 3500);
PAINT GREEN (-2927 3500);
DISPLAY INVISIBLE (-2927 3500);
FORCEADD TAP..1
(-2925 3450);
FORCEPROP 3 LASTPIN (-2975 3450) SIG_NAME UPI_CPU0_CPU1_P0P0_DP<3>
J 0
(-2965 3460);
DISPLAY 0.659574 (-2965 3460);
PAINT MONO (-2965 3460);
DISPLAY INVISIBLE (-2965 3460);
FORCEPROP 1 LASTPIN (-2975 3450) BN 3
J 0
(-2987 3458);
DISPLAY 0.617021 (-2987 3458);
PAINT PINK (-2987 3458);
FORCEPROP 2 LAST CDS_LIB mstr_standard
J 0
(-2925 3450);
PAINT MONO (-2925 3450);
DISPLAY INVISIBLE (-2925 3450);
FORCEPROP 1 LAST BODY_TYPE PLUMBING
J 0
(-2925 3500);
DISPLAY 1.446809 (-2925 3500);
PAINT GREEN (-2925 3500);
DISPLAY INVISIBLE (-2925 3500);
FORCEPROP 1 LAST HDL_TAP TRUE
J 0
(-2600 3325);
DISPLAY 1.446809 (-2600 3325);
PAINT GREEN (-2600 3325);
DISPLAY INVISIBLE (-2600 3325);
FORCEPROP 1 LAST PATH I82
J 0
(-2927 3450);
DISPLAY 0.872340 (-2927 3450);
PAINT GREEN (-2927 3450);
DISPLAY INVISIBLE (-2927 3450);
FORCEADD TAP..1
(-2925 3600);
FORCEPROP 3 LASTPIN (-2975 3600) SIG_NAME UPI_CPU0_CPU1_P0P0_DP<0>
J 0
(-2965 3610);
DISPLAY 0.659574 (-2965 3610);
PAINT MONO (-2965 3610);
DISPLAY INVISIBLE (-2965 3610);
FORCEPROP 1 LASTPIN (-2975 3600) BN 0
J 0
(-2987 3608);
DISPLAY 0.617021 (-2987 3608);
PAINT PINK (-2987 3608);
FORCEPROP 2 LAST CDS_LIB mstr_standard
J 2
(-2925 3600);
PAINT MONO (-2925 3600);
DISPLAY INVISIBLE (-2925 3600);
FORCEPROP 1 LAST BODY_TYPE PLUMBING
J 0
(-2925 3650);
DISPLAY 1.446809 (-2925 3650);
PAINT GREEN (-2925 3650);
DISPLAY INVISIBLE (-2925 3650);
FORCEPROP 1 LAST HDL_TAP TRUE
J 0
(-2600 3475);
DISPLAY 1.446809 (-2600 3475);
PAINT GREEN (-2600 3475);
DISPLAY INVISIBLE (-2600 3475);
FORCEPROP 1 LAST PATH I83
J 0
(-2927 3600);
DISPLAY 0.872340 (-2927 3600);
PAINT GREEN (-2927 3600);
DISPLAY INVISIBLE (-2927 3600);
FORCEADD OFFPAGE..2
(-1725 2600);
FORCEPROP 2 LAST $XR0 67 
J 0
(-1536 2600);
DISPLAY 0.638298 (-1536 2600);
PAINT MONO (-1536 2600);
FORCEPROP 2 LAST CDS_LIB mstr_standard
J 0
(-1725 2600);
PAINT MONO (-1725 2600);
DISPLAY INVISIBLE (-1725 2600);
FORCEPROP 1 LAST OFFPAGE TRUE
J 0
(-1400 2475);
DISPLAY 1.170213 (-1400 2475);
PAINT GREEN (-1400 2475);
DISPLAY INVISIBLE (-1400 2475);
FORCEPROP 1 LAST COMMENT_BODY TRUE
J 0
(-1770 2505);
DISPLAY 1.170213 (-1770 2505);
PAINT GREEN (-1770 2505);
DISPLAY INVISIBLE (-1770 2505);
FORCEPROP 2 LAST PATH I84
J 0
(-1550 2675);
DISPLAY 1.021277 (-1550 2675);
PAINT ORANGE (-1550 2675);
DISPLAY INVISIBLE (-1550 2675);
FORCEADD OFFPAGE..2
(-1725 3650);
FORCEPROP 2 LAST $XR0 67 
J 0
(-1536 3650);
DISPLAY 0.638298 (-1536 3650);
PAINT MONO (-1536 3650);
FORCEPROP 2 LAST CDS_LIB mstr_standard
J 0
(-1725 3650);
PAINT MONO (-1725 3650);
DISPLAY INVISIBLE (-1725 3650);
FORCEPROP 1 LAST OFFPAGE TRUE
J 0
(-1400 3525);
DISPLAY 1.170213 (-1400 3525);
PAINT GREEN (-1400 3525);
DISPLAY INVISIBLE (-1400 3525);
FORCEPROP 1 LAST COMMENT_BODY TRUE
J 0
(-1770 3555);
DISPLAY 1.170213 (-1770 3555);
PAINT GREEN (-1770 3555);
DISPLAY INVISIBLE (-1770 3555);
FORCEPROP 2 LAST PATH I85
J 0
(-1550 3725);
DISPLAY 1.021277 (-1550 3725);
PAINT ORANGE (-1550 3725);
DISPLAY INVISIBLE (-1550 3725);
FORCEADD SKX_EXT_B..13
(-4075 2600);
FORCEPROP 1 LAST LOCATION U5D1
J 0
(-4825 3850);
DISPLAY 0.617021 (-4825 3850);
PAINT AQUA (-4825 3850);
FORCEPROP 1 LAST PART_NUMBER TBD
J 0
(-4825 1400);
DISPLAY 0.617021 (-4825 1400);
PAINT BLUE (-4825 1400);
FORCEPROP 1 LAST MATERIAL IC
J 0
(-4825 3800);
DISPLAY 0.617021 (-4825 3800);
PAINT SKYBLUE (-4825 3800);
FORCEPROP 2 LASTPIN (-3275 3600) $PN BH3
J 0
(-3265 3610);
DISPLAY 0.617021 (-3265 3610);
PAINT ORANGE (-3265 3610);
FORCEPROP 2 LASTPIN (-3275 3550) $PN BD3
J 0
(-3265 3560);
DISPLAY 0.617021 (-3265 3560);
PAINT ORANGE (-3265 3560);
FORCEPROP 2 LASTPIN (-3275 3500) $PN BC2
J 0
(-3265 3510);
DISPLAY 0.617021 (-3265 3510);
PAINT ORANGE (-3265 3510);
FORCEPROP 2 LASTPIN (-3275 3450) $PN AY3
J 0
(-3265 3460);
DISPLAY 0.617021 (-3265 3460);
PAINT ORANGE (-3265 3460);
FORCEPROP 2 LASTPIN (-3275 3400) $PN AW4
J 0
(-3265 3410);
DISPLAY 0.617021 (-3265 3410);
PAINT ORANGE (-3265 3410);
FORCEPROP 2 LASTPIN (-3275 3350) $PN AR4
J 0
(-3265 3360);
DISPLAY 0.617021 (-3265 3360);
PAINT ORANGE (-3265 3360);
FORCEPROP 2 LASTPIN (-3275 3300) $PN AR2
J 0
(-3265 3310);
DISPLAY 0.617021 (-3265 3310);
PAINT ORANGE (-3265 3310);
FORCEPROP 2 LASTPIN (-3275 3250) $PN AP1
J 0
(-3265 3260);
DISPLAY 0.617021 (-3265 3260);
PAINT ORANGE (-3265 3260);
FORCEPROP 2 LASTPIN (-3275 3200) $PN AP3
J 0
(-3265 3210);
DISPLAY 0.617021 (-3265 3210);
PAINT ORANGE (-3265 3210);
FORCEPROP 2 LASTPIN (-3275 3150) $PN AK3
J 0
(-3265 3160);
DISPLAY 0.617021 (-3265 3160);
PAINT ORANGE (-3265 3160);
FORCEPROP 2 LASTPIN (-3275 3100) $PN AK1
J 0
(-3265 3110);
DISPLAY 0.617021 (-3265 3110);
PAINT ORANGE (-3265 3110);
FORCEPROP 2 LASTPIN (-3275 3050) $PN AJ2
J 0
(-3265 3060);
DISPLAY 0.617021 (-3265 3060);
PAINT ORANGE (-3265 3060);
FORCEPROP 2 LASTPIN (-3275 3000) $PN AG2
J 0
(-3265 3010);
DISPLAY 0.617021 (-3265 3010);
PAINT ORANGE (-3265 3010);
FORCEPROP 2 LASTPIN (-3275 2950) $PN AF3
J 0
(-3265 2960);
DISPLAY 0.617021 (-3265 2960);
PAINT ORANGE (-3265 2960);
FORCEPROP 2 LASTPIN (-3275 2900) $PN AD1
J 0
(-3265 2910);
DISPLAY 0.617021 (-3265 2910);
PAINT ORANGE (-3265 2910);
FORCEPROP 2 LASTPIN (-3275 2850) $PN AA2
J 0
(-3265 2860);
DISPLAY 0.617021 (-3265 2860);
PAINT ORANGE (-3265 2860);
FORCEPROP 2 LASTPIN (-3275 2800) $PN W2
J 0
(-3265 2810);
DISPLAY 0.617021 (-3265 2810);
PAINT ORANGE (-3265 2810);
FORCEPROP 2 LASTPIN (-3275 2750) $PN Y3
J 0
(-3265 2760);
DISPLAY 0.617021 (-3265 2760);
PAINT ORANGE (-3265 2760);
FORCEPROP 2 LASTPIN (-3275 2700) $PN T1
J 0
(-3265 2710);
DISPLAY 0.617021 (-3265 2710);
PAINT ORANGE (-3265 2710);
FORCEPROP 2 LASTPIN (-3275 2650) $PN M1
J 0
(-3265 2660);
DISPLAY 0.617021 (-3265 2660);
PAINT ORANGE (-3265 2660);
FORCEPROP 2 LASTPIN (-3275 2550) $PN BG4
J 0
(-3265 2560);
DISPLAY 0.617021 (-3265 2560);
PAINT ORANGE (-3265 2560);
FORCEPROP 2 LASTPIN (-3275 2500) $PN BF3
J 0
(-3265 2510);
DISPLAY 0.617021 (-3265 2510);
PAINT ORANGE (-3265 2510);
FORCEPROP 2 LASTPIN (-3275 2450) $PN BB3
J 0
(-3265 2460);
DISPLAY 0.617021 (-3265 2460);
PAINT ORANGE (-3265 2460);
FORCEPROP 2 LASTPIN (-3275 2400) $PN BA4
J 0
(-3265 2410);
DISPLAY 0.617021 (-3265 2410);
PAINT ORANGE (-3265 2410);
FORCEPROP 2 LASTPIN (-3275 2350) $PN AV5
J 0
(-3265 2360);
DISPLAY 0.617021 (-3265 2360);
PAINT ORANGE (-3265 2360);
FORCEPROP 2 LASTPIN (-3275 2300) $PN AU4
J 0
(-3265 2310);
DISPLAY 0.617021 (-3265 2310);
PAINT ORANGE (-3265 2310);
FORCEPROP 2 LASTPIN (-3275 2250) $PN AT3
J 0
(-3265 2260);
DISPLAY 0.617021 (-3265 2260);
PAINT ORANGE (-3265 2260);
FORCEPROP 2 LASTPIN (-3275 2200) $PN AT1
J 0
(-3265 2210);
DISPLAY 0.617021 (-3265 2210);
PAINT ORANGE (-3265 2210);
FORCEPROP 2 LASTPIN (-3275 2150) $PN AN4
J 0
(-3265 2160);
DISPLAY 0.617021 (-3265 2160);
PAINT ORANGE (-3265 2160);
FORCEPROP 2 LASTPIN (-3275 2100) $PN AM3
J 0
(-3265 2110);
DISPLAY 0.617021 (-3265 2110);
PAINT ORANGE (-3265 2110);
FORCEPROP 2 LASTPIN (-3275 2050) $PN AL2
J 0
(-3265 2060);
DISPLAY 0.617021 (-3265 2060);
PAINT ORANGE (-3265 2060);
FORCEPROP 2 LASTPIN (-3275 2000) $PN AH3
J 0
(-3265 2010);
DISPLAY 0.617021 (-3265 2010);
PAINT ORANGE (-3265 2010);
FORCEPROP 2 LASTPIN (-3275 1950) $PN AE2
J 0
(-3265 1960);
DISPLAY 0.617021 (-3265 1960);
PAINT ORANGE (-3265 1960);
FORCEPROP 2 LASTPIN (-3275 1900) $PN AG4
J 0
(-3265 1910);
DISPLAY 0.617021 (-3265 1910);
PAINT ORANGE (-3265 1910);
FORCEPROP 2 LASTPIN (-3275 1850) $PN AC2
J 0
(-3265 1860);
DISPLAY 0.617021 (-3265 1860);
PAINT ORANGE (-3265 1860);
FORCEPROP 2 LASTPIN (-3275 1800) $PN AB3
J 0
(-3265 1810);
DISPLAY 0.617021 (-3265 1810);
PAINT ORANGE (-3265 1810);
FORCEPROP 2 LASTPIN (-3275 1750) $PN Y1
J 0
(-3265 1760);
DISPLAY 0.617021 (-3265 1760);
PAINT ORANGE (-3265 1760);
FORCEPROP 2 LASTPIN (-3275 1700) $PN V3
J 0
(-3265 1710);
DISPLAY 0.617021 (-3265 1710);
PAINT ORANGE (-3265 1710);
FORCEPROP 2 LASTPIN (-3275 1650) $PN P1
J 0
(-3265 1660);
DISPLAY 0.617021 (-3265 1660);
PAINT ORANGE (-3265 1660);
FORCEPROP 2 LASTPIN (-3275 1600) $PN N2
J 0
(-3265 1610);
DISPLAY 0.617021 (-3265 1610);
PAINT ORANGE (-3265 1610);
FORCEPROP 2 LASTPIN (-4875 3600) $PN BA10
J 2
(-4885 3610);
DISPLAY 0.617021 (-4885 3610);
PAINT ORANGE (-4885 3610);
FORCEPROP 2 LASTPIN (-4875 3550) $PN BC10
J 2
(-4885 3560);
DISPLAY 0.617021 (-4885 3560);
PAINT ORANGE (-4885 3560);
FORCEPROP 2 LASTPIN (-4875 3500) $PN BB9
J 2
(-4885 3510);
DISPLAY 0.617021 (-4885 3510);
PAINT ORANGE (-4885 3510);
FORCEPROP 2 LASTPIN (-4875 3450) $PN AV9
J 2
(-4885 3460);
DISPLAY 0.617021 (-4885 3460);
PAINT ORANGE (-4885 3460);
FORCEPROP 2 LASTPIN (-4875 3400) $PN BF7
J 2
(-4885 3410);
DISPLAY 0.617021 (-4885 3410);
PAINT ORANGE (-4885 3410);
FORCEPROP 2 LASTPIN (-4875 3350) $PN BB7
J 2
(-4885 3360);
DISPLAY 0.617021 (-4885 3360);
PAINT ORANGE (-4885 3360);
FORCEPROP 2 LASTPIN (-4875 3300) $PN AY7
J 2
(-4885 3310);
DISPLAY 0.617021 (-4885 3310);
PAINT ORANGE (-4885 3310);
FORCEPROP 2 LASTPIN (-4875 3250) $PN AT9
J 2
(-4885 3260);
DISPLAY 0.617021 (-4885 3260);
PAINT ORANGE (-4885 3260);
FORCEPROP 2 LASTPIN (-4875 3200) $PN AU8
J 2
(-4885 3210);
DISPLAY 0.617021 (-4885 3210);
PAINT ORANGE (-4885 3210);
FORCEPROP 2 LASTPIN (-4875 3150) $PN AN8
J 2
(-4885 3160);
DISPLAY 0.617021 (-4885 3160);
PAINT ORANGE (-4885 3160);
FORCEPROP 2 LASTPIN (-4875 3100) $PN AL8
J 2
(-4885 3110);
DISPLAY 0.617021 (-4885 3110);
PAINT ORANGE (-4885 3110);
FORCEPROP 2 LASTPIN (-4875 3050) $PN AM7
J 2
(-4885 3060);
DISPLAY 0.617021 (-4885 3060);
PAINT ORANGE (-4885 3060);
FORCEPROP 2 LASTPIN (-4875 3000) $PN AK5
J 2
(-4885 3010);
DISPLAY 0.617021 (-4885 3010);
PAINT ORANGE (-4885 3010);
FORCEPROP 2 LASTPIN (-4875 2950) $PN AH7
J 2
(-4885 2960);
DISPLAY 0.617021 (-4885 2960);
PAINT ORANGE (-4885 2960);
FORCEPROP 2 LASTPIN (-4875 2900) $PN AF7
J 2
(-4885 2910);
DISPLAY 0.617021 (-4885 2910);
PAINT ORANGE (-4885 2910);
FORCEPROP 2 LASTPIN (-4875 2850) $PN AG6
J 2
(-4885 2860);
DISPLAY 0.617021 (-4885 2860);
PAINT ORANGE (-4885 2860);
FORCEPROP 2 LASTPIN (-4875 2800) $PN AC6
J 2
(-4885 2810);
DISPLAY 0.617021 (-4885 2810);
PAINT ORANGE (-4885 2810);
FORCEPROP 2 LASTPIN (-4875 2750) $PN AA6
J 2
(-4885 2760);
DISPLAY 0.617021 (-4885 2760);
PAINT ORANGE (-4885 2760);
FORCEPROP 2 LASTPIN (-4875 2700) $PN AC8
J 2
(-4885 2710);
DISPLAY 0.617021 (-4885 2710);
PAINT ORANGE (-4885 2710);
FORCEPROP 2 LASTPIN (-4875 2650) $PN AB9
J 2
(-4885 2660);
DISPLAY 0.617021 (-4885 2660);
PAINT ORANGE (-4885 2660);
FORCEPROP 2 LASTPIN (-4875 2550) $PN BB11
J 2
(-4885 2560);
DISPLAY 0.617021 (-4885 2560);
PAINT ORANGE (-4885 2560);
FORCEPROP 2 LASTPIN (-4875 2500) $PN BD9
J 2
(-4885 2510);
DISPLAY 0.617021 (-4885 2510);
PAINT ORANGE (-4885 2510);
FORCEPROP 2 LASTPIN (-4875 2450) $PN AY9
J 2
(-4885 2460);
DISPLAY 0.617021 (-4885 2460);
PAINT ORANGE (-4885 2460);
FORCEPROP 2 LASTPIN (-4875 2400) $PN AW8
J 2
(-4885 2410);
DISPLAY 0.617021 (-4885 2410);
PAINT ORANGE (-4885 2410);
FORCEPROP 2 LASTPIN (-4875 2350) $PN BD7
J 2
(-4885 2360);
DISPLAY 0.617021 (-4885 2360);
PAINT ORANGE (-4885 2360);
FORCEPROP 2 LASTPIN (-4875 2300) $PN BC6
J 2
(-4885 2310);
DISPLAY 0.617021 (-4885 2310);
PAINT ORANGE (-4885 2310);
FORCEPROP 2 LASTPIN (-4875 2250) $PN BA8
J 2
(-4885 2260);
DISPLAY 0.617021 (-4885 2260);
PAINT ORANGE (-4885 2260);
FORCEPROP 2 LASTPIN (-4875 2200) $PN AU10
J 2
(-4885 2210);
DISPLAY 0.617021 (-4885 2210);
PAINT ORANGE (-4885 2210);
FORCEPROP 2 LASTPIN (-4875 2150) $PN AR8
J 2
(-4885 2160);
DISPLAY 0.617021 (-4885 2160);
PAINT ORANGE (-4885 2160);
FORCEPROP 2 LASTPIN (-4875 2100) $PN AP7
J 2
(-4885 2110);
DISPLAY 0.617021 (-4885 2110);
PAINT ORANGE (-4885 2110);
FORCEPROP 2 LASTPIN (-4875 2050) $PN AM9
J 2
(-4885 2060);
DISPLAY 0.617021 (-4885 2060);
PAINT ORANGE (-4885 2060);
FORCEPROP 2 LASTPIN (-4875 2000) $PN AK7
J 2
(-4885 2010);
DISPLAY 0.617021 (-4885 2010);
PAINT ORANGE (-4885 2010);
FORCEPROP 2 LASTPIN (-4875 1950) $PN AL6
J 2
(-4885 1960);
DISPLAY 0.617021 (-4885 1960);
PAINT ORANGE (-4885 1960);
FORCEPROP 2 LASTPIN (-4875 1900) $PN AJ6
J 2
(-4885 1910);
DISPLAY 0.617021 (-4885 1910);
PAINT ORANGE (-4885 1910);
FORCEPROP 2 LASTPIN (-4875 1850) $PN AG8
J 2
(-4885 1860);
DISPLAY 0.617021 (-4885 1860);
PAINT ORANGE (-4885 1860);
FORCEPROP 2 LASTPIN (-4875 1800) $PN AE6
J 2
(-4885 1810);
DISPLAY 0.617021 (-4885 1810);
PAINT ORANGE (-4885 1810);
FORCEPROP 2 LASTPIN (-4875 1750) $PN AD5
J 2
(-4885 1760);
DISPLAY 0.617021 (-4885 1760);
PAINT ORANGE (-4885 1760);
FORCEPROP 2 LASTPIN (-4875 1700) $PN AB7
J 2
(-4885 1710);
DISPLAY 0.617021 (-4885 1710);
PAINT ORANGE (-4885 1710);
FORCEPROP 2 LASTPIN (-4875 1650) $PN AA8
J 2
(-4885 1660);
DISPLAY 0.617021 (-4885 1660);
PAINT ORANGE (-4885 1660);
FORCEPROP 2 LASTPIN (-4875 1600) $PN AC10
J 2
(-4885 1610);
DISPLAY 0.617021 (-4885 1610);
PAINT ORANGE (-4885 1610);
FORCEPROP 1 LAST PACK_TYPE BGA1
J 0
(-4825 3900);
PAINT SKYBLUE (-4825 3900);
DISPLAY INVISIBLE (-4825 3900);
FORCEPROP 2 LAST CDS_LIB chpset_lib
J 0
(-4075 2600);
PAINT ORANGE (-4075 2600);
DISPLAY INVISIBLE (-4075 2600);
FORCEPROP 2 LAST SEC_TYPE BGA1
J 0
(-4825 3900);
DISPLAY 1.021277 (-4825 3900);
PAINT ORANGE (-4825 3900);
DISPLAY INVISIBLE (-4825 3900);
FORCEPROP 2 LAST SEC 13
J 0
(-4825 3900);
DISPLAY 0.680851 (-4825 3900);
PAINT MONO (-4825 3900);
DISPLAY INVISIBLE (-4825 3900);
FORCEPROP 2 LAST CDS_LOCATION U5D1
J 0
(-4825 3850);
DISPLAY 0.617021 (-4825 3850);
PAINT AQUA (-4825 3850);
DISPLAY INVISIBLE (-4825 3850);
FORCEPROP 1 LAST PATH I86
J 0
(-4075 3800);
PAINT GREEN (-4075 3800);
DISPLAY INVISIBLE (-4075 3800);
FORCEPROP 0 LAST ROOM CPU0
J 0
(-4825 3950);
DISPLAY 1.021277 (-4825 3950);
PAINT ORANGE (-4825 3950);
DISPLAY INVISIBLE (-4825 3950);
FORCEADD TAP..1
R 2
(-5250 1950);
FORCEPROP 3 LASTPIN (-5200 1950) SIG_NAME UPI_CPU1_CPU0_P0P0_DN<12>
J 0
(-5190 1960);
DISPLAY 0.659574 (-5190 1960);
PAINT MONO (-5190 1960);
DISPLAY INVISIBLE (-5190 1960);
FORCEPROP 1 LASTPIN (-5200 1950) BN 12
J 2
(-5188 1958);
DISPLAY 0.617021 (-5188 1958);
PAINT PINK (-5188 1958);
FORCEPROP 2 LAST CDS_LIB mstr_standard
J 0
(-5250 1950);
PAINT MONO (-5250 1950);
DISPLAY INVISIBLE (-5250 1950);
FORCEPROP 1 LAST BODY_TYPE PLUMBING
J 2
(-5250 2000);
DISPLAY 1.446809 (-5250 2000);
PAINT GREEN (-5250 2000);
DISPLAY INVISIBLE (-5250 2000);
FORCEPROP 1 LAST HDL_TAP TRUE
J 2
(-5575 1825);
DISPLAY 1.446809 (-5575 1825);
PAINT GREEN (-5575 1825);
DISPLAY INVISIBLE (-5575 1825);
FORCEPROP 1 LAST PATH I9
J 2
(-5248 1950);
DISPLAY 0.872340 (-5248 1950);
PAINT GREEN (-5248 1950);
DISPLAY INVISIBLE (-5248 1950);
FORCEADD DESIGN_NOTE..1
(-4675 1275);
FORCEPROP 0 LAST L1 CPU SYMBOLS 1-30 ARE PRELIMINARY AND SUBJECT TO CHANGE
J 0
(-4875 1150);
DISPLAY 1.021277 (-4875 1150);
PAINT ORANGE (-4875 1150);
FORCEPROP 2 LAST CDS_LIB mstr_symbols
J 0
(-4675 1275);
PAINT ORANGE (-4675 1275);
DISPLAY INVISIBLE (-4675 1275);
FORCEPROP 1 LAST COMMENT_BODY TRUE
J 0
(-4650 1375);
DISPLAY 0.978723 (-4650 1375);
PAINT ORANGE (-4650 1375);
DISPLAY INVISIBLE (-4650 1375);
FORCEADD PRELIM..10
(-4065 2590);
PAINT GRAY (-4065 2590);
FORCEPROP 2 LAST CDS_LIB mstr_misc
J 0
(-4065 2590);
PAINT ORANGE (-4065 2590);
DISPLAY INVISIBLE (-4065 2590);
FORCEPROP 1 LAST COMMENT_BODY TRUE
J 0
(-4065 2590);
PAINT ORANGE (-4065 2590);
DISPLAY INVISIBLE (-4065 2590);
FORCEADD INTEL_CORP_BPAGE..1
(0 0);
FORCEPROP 1 LAST CDS_CON_LAST_MODIFIED Tue Dec 01 11:51:21 2015
J 0
(-1425 325);
DISPLAY 1.340426 (-1425 325);
PAINT GREEN (-1425 325);
DISPLAY INVISIBLE (-1425 325);
FORCEPROP 1 LAST CUSTOM_TXT_CDS <CURRENT_DESIGN_SHEET> OF <TOTAL_DESIGN_SHEETS>
J 0
(-500 25);
PAINT GREEN (-500 25);
FORCEPROP 1 LAST CUSTOM_TXT_CDS <CON_LAST_MODIFIED>
J 0
(-1925 350);
PAINT GREEN (-1925 350);
FORCEPROP 2 LAST CUSTOM_TXT_CDS <XR_PAGE_TITLE>
J 0
(-7890 5250);
DISPLAY 0.638298 (-7890 5250);
PAINT PINK (-7890 5250);
DISPLAY INVISIBLE (-7890 5250);
FORCEPROP 1 LAST SCH_ADDRESS3 Santa Clara, CA 95052-8119
J 0
(-3975 25);
DISPLAY 0.617021 (-3975 25);
PAINT GREEN (-3975 25);
FORCEPROP 1 LAST SCH_ADDRESS2 P.O. BOX 58119
J 0
(-3975 75);
DISPLAY 0.617021 (-3975 75);
PAINT GREEN (-3975 75);
FORCEPROP 1 LAST SCH_ADDRESS1 2200 Mission College Blvd.
J 0
(-3975 125);
DISPLAY 0.617021 (-3975 125);
PAINT GREEN (-3975 125);
FORCEPROP 1 LAST SCH_TITLE SKYLAKE - SKT0 - 13 OF 21
J 0
(-7950 50);
DISPLAY 1.212766 (-7950 50);
PAINT GREEN (-7950 50);
FORCEPROP 1 LAST SCH_NUMBER H4694802
J 0
(-1300 150);
DISPLAY 1.212766 (-1300 150);
PAINT YELLOW (-1300 150);
FORCEPROP 1 LAST SCH_DEPT BESD
J 1
(-4450 100);
DISPLAY 1.212766 (-4450 100);
PAINT YELLOW (-4450 100);
FORCEPROP 1 LAST SCH_REV 2.420
J 0
(-250 150);
DISPLAY 0.978723 (-250 150);
PAINT YELLOW (-250 150);
FORCEPROP 2 LAST PAGE_BORDER TRUE
J 0
(-7890 5250);
DISPLAY 0.851064 (-7890 5250);
PAINT PINK (-7890 5250);
DISPLAY INVISIBLE (-7890 5250);
FORCEPROP 2 LAST CDS_LIB mstr_symbols
J 0
(0 0);
PAINT ORANGE (0 0);
DISPLAY INVISIBLE (0 0);
FORCEPROP 1 LAST COMMENT_BODY TRUE
J 0
(12 12);
DISPLAY 0.638298 (12 12);
PAINT GREEN (12 12);
DISPLAY INVISIBLE (12 12);
FORCEPROP 2 LAST CDS_XR_PAGE_TITLE CR-33 : @BASEBOARD_FAB2_LIB.BASEBOARD_FAB2(SCH_1):PAGE33
J 0
(-7890 5250);
DISPLAY 0.638298 (-7890 5250);
PAINT PINK (-7890 5250);
DISPLAY INVISIBLE (-7890 5250);
WIRE 17 -1 (-2875 2600)(-2875 2575);
WIRE 17 -1 (-2875 2600)(-1775 2600);
FORCEPROP 2 LAST SIG_NAME UPI_CPU0_CPU1_P0P0_DN<19..0>
J 0
(-2785 2610);
DISPLAY 0.617021 (-2785 2610);
PAINT ORANGE (-2785 2610);
WIRE 17 -1 (-2875 2575)(-2875 2525);
WIRE 17 -1 (-2875 2525)(-2875 2475);
WIRE 17 -1 (-2875 2475)(-2875 2425);
WIRE 17 -1 (-2875 2425)(-2875 2375);
WIRE 17 -1 (-2875 2375)(-2875 2325);
WIRE 17 -1 (-2875 2325)(-2875 2275);
WIRE 17 -1 (-2875 2275)(-2875 2225);
WIRE 17 -1 (-2875 2225)(-2875 2175);
WIRE 17 -1 (-2875 2175)(-2875 2125);
WIRE 17 -1 (-2875 2125)(-2875 2075);
WIRE 17 -1 (-2875 2075)(-2875 2025);
WIRE 17 -1 (-2875 2025)(-2875 1975);
WIRE 17 -1 (-2875 1975)(-2875 1925);
WIRE 17 -1 (-2875 1925)(-2875 1875);
WIRE 17 -1 (-2875 1875)(-2875 1825);
WIRE 17 -1 (-2875 1825)(-2875 1775);
WIRE 17 -1 (-2875 1775)(-2875 1725);
WIRE 17 -1 (-2875 1725)(-2875 1675);
WIRE 17 -1 (-2875 1675)(-2875 1625);
WIRE 17 -1 (-2875 3650)(-2875 3625);
WIRE 17 -1 (-2875 3650)(-1775 3650);
FORCEPROP 2 LAST SIG_NAME UPI_CPU0_CPU1_P0P0_DP<19..0>
J 0
(-2785 3660);
DISPLAY 0.617021 (-2785 3660);
PAINT ORANGE (-2785 3660);
WIRE 17 -1 (-2875 3625)(-2875 3575);
WIRE 17 -1 (-2875 3575)(-2875 3525);
WIRE 17 -1 (-2875 3525)(-2875 3475);
WIRE 17 -1 (-2875 3475)(-2875 3425);
WIRE 17 -1 (-2875 3425)(-2875 3375);
WIRE 17 -1 (-2875 3375)(-2875 3325);
WIRE 17 -1 (-2875 3325)(-2875 3275);
WIRE 17 -1 (-2875 3275)(-2875 3225);
WIRE 17 -1 (-2875 3225)(-2875 3175);
WIRE 17 -1 (-2875 3175)(-2875 3125);
WIRE 17 -1 (-2875 3125)(-2875 3075);
WIRE 17 -1 (-2875 3075)(-2875 3025);
WIRE 17 -1 (-2875 3025)(-2875 2975);
WIRE 17 -1 (-2875 2975)(-2875 2925);
WIRE 17 -1 (-2875 2925)(-2875 2875);
WIRE 17 -1 (-2875 2875)(-2875 2825);
WIRE 17 -1 (-2875 2825)(-2875 2775);
WIRE 17 -1 (-2875 2775)(-2875 2725);
WIRE 17 -1 (-2875 2725)(-2875 2675);
WIRE 17 -1 (-5300 2525)(-5300 2575);
WIRE 17 -1 (-5300 2475)(-5300 2525);
WIRE 17 -1 (-5300 2575)(-5300 2600);
WIRE 17 -1 (-6400 2600)(-5300 2600);
FORCEPROP 2 LAST SIG_NAME UPI_CPU1_CPU0_P0P0_DN<19..0>
J 0
(-6335 2610);
DISPLAY 0.617021 (-6335 2610);
PAINT ORANGE (-6335 2610);
WIRE 17 -1 (-5300 2475)(-5300 2425);
WIRE 17 -1 (-5300 2425)(-5300 2375);
WIRE 17 -1 (-5300 2375)(-5300 2325);
WIRE 17 -1 (-5300 2325)(-5300 2275);
WIRE 17 -1 (-5300 2275)(-5300 2225);
WIRE 17 -1 (-5300 2225)(-5300 2175);
WIRE 17 -1 (-5300 2175)(-5300 2125);
WIRE 17 -1 (-5300 2125)(-5300 2075);
WIRE 17 -1 (-5300 2075)(-5300 2025);
WIRE 17 -1 (-5300 2025)(-5300 1975);
WIRE 17 -1 (-5300 1975)(-5300 1925);
WIRE 17 -1 (-5300 1925)(-5300 1875);
WIRE 17 -1 (-5300 1875)(-5300 1825);
WIRE 17 -1 (-5300 1825)(-5300 1775);
WIRE 17 -1 (-5300 1775)(-5300 1725);
WIRE 17 -1 (-5300 1675)(-5300 1725);
WIRE 17 -1 (-5300 1625)(-5300 1675);
WIRE 17 -1 (-5300 3575)(-5300 3625);
WIRE 17 -1 (-5300 3525)(-5300 3575);
WIRE 17 -1 (-5300 3650)(-5300 3625);
WIRE 17 -1 (-6400 3650)(-5300 3650);
FORCEPROP 2 LAST SIG_NAME UPI_CPU1_CPU0_P0P0_DP<19..0>
J 0
(-6310 3660);
DISPLAY 0.617021 (-6310 3660);
PAINT ORANGE (-6310 3660);
WIRE 17 -1 (-5300 3525)(-5300 3475);
WIRE 17 -1 (-5300 3475)(-5300 3425);
WIRE 17 -1 (-5300 3425)(-5300 3375);
WIRE 17 -1 (-5300 3375)(-5300 3325);
WIRE 17 -1 (-5300 3325)(-5300 3275);
WIRE 17 -1 (-5300 3275)(-5300 3225);
WIRE 17 -1 (-5300 3225)(-5300 3175);
WIRE 17 -1 (-5300 3175)(-5300 3125);
WIRE 17 -1 (-5300 3125)(-5300 3075);
WIRE 17 -1 (-5300 3075)(-5300 3025);
WIRE 17 -1 (-5300 3025)(-5300 2975);
WIRE 17 -1 (-5300 2975)(-5300 2925);
WIRE 17 -1 (-5300 2925)(-5300 2875);
WIRE 17 -1 (-5300 2875)(-5300 2825);
WIRE 17 -1 (-5300 2825)(-5300 2775);
WIRE 17 -1 (-5300 2725)(-5300 2775);
WIRE 17 -1 (-5300 2675)(-5300 2725);
WIRE 16 -1 (-5200 1600)(-4875 1600);
WIRE 16 -1 (-5200 1650)(-4875 1650);
WIRE 16 -1 (-5200 1700)(-4875 1700);
WIRE 16 -1 (-5200 1750)(-4875 1750);
WIRE 16 -1 (-5200 1800)(-4875 1800);
WIRE 16 -1 (-5200 1850)(-4875 1850);
WIRE 16 -1 (-5200 1900)(-4875 1900);
WIRE 16 -1 (-5200 1950)(-4875 1950);
WIRE 16 -1 (-5200 2000)(-4875 2000);
WIRE 16 -1 (-5200 2650)(-4875 2650);
WIRE 16 -1 (-5200 2700)(-4875 2700);
WIRE 16 -1 (-5200 2750)(-4875 2750);
WIRE 16 -1 (-5200 2800)(-4875 2800);
WIRE 16 -1 (-5200 2850)(-4875 2850);
WIRE 16 -1 (-5200 2900)(-4875 2900);
WIRE 16 -1 (-5200 2950)(-4875 2950);
WIRE 16 -1 (-5200 3000)(-4875 3000);
WIRE 16 -1 (-5200 3050)(-4875 3050);
WIRE 16 -1 (-5200 3100)(-4875 3100);
WIRE 16 -1 (-5200 3150)(-4875 3150);
WIRE 16 -1 (-5200 3200)(-4875 3200);
WIRE 16 -1 (-5200 3250)(-4875 3250);
WIRE 16 -1 (-5200 3300)(-4875 3300);
WIRE 16 -1 (-5200 3350)(-4875 3350);
WIRE 16 -1 (-5200 3400)(-4875 3400);
WIRE 16 -1 (-5200 3450)(-4875 3450);
WIRE 16 -1 (-5200 3500)(-4875 3500);
WIRE 16 -1 (-5200 3550)(-4875 3550);
WIRE 16 -1 (-5200 3600)(-4875 3600);
WIRE 16 -1 (-5200 2050)(-4875 2050);
WIRE 16 -1 (-5200 2100)(-4875 2100);
WIRE 16 -1 (-5200 2150)(-4875 2150);
WIRE 16 -1 (-5200 2200)(-4875 2200);
WIRE 16 -1 (-5200 2250)(-4875 2250);
WIRE 16 -1 (-5200 2300)(-4875 2300);
WIRE 16 -1 (-5200 2350)(-4875 2350);
WIRE 16 -1 (-5200 2400)(-4875 2400);
WIRE 16 -1 (-5200 2450)(-4875 2450);
WIRE 16 -1 (-5200 2500)(-4875 2500);
WIRE 16 -1 (-5200 2550)(-4875 2550);
WIRE 16 -1 (-2975 1600)(-3275 1600);
WIRE 16 -1 (-2975 1650)(-3275 1650);
WIRE 16 -1 (-2975 1700)(-3275 1700);
WIRE 16 -1 (-2975 1750)(-3275 1750);
WIRE 16 -1 (-3275 1800)(-2975 1800);
WIRE 16 -1 (-2975 1850)(-3275 1850);
WIRE 16 -1 (-3275 1900)(-2975 1900);
WIRE 16 -1 (-2975 1950)(-3275 1950);
WIRE 16 -1 (-2975 2000)(-3275 2000);
WIRE 16 -1 (-2975 2650)(-3275 2650);
WIRE 16 -1 (-2975 2700)(-3275 2700);
WIRE 16 -1 (-3275 2750)(-2975 2750);
WIRE 16 -1 (-2975 2800)(-3275 2800);
WIRE 16 -1 (-2975 2850)(-3275 2850);
WIRE 16 -1 (-2975 2900)(-3275 2900);
WIRE 16 -1 (-2975 2950)(-3275 2950);
WIRE 16 -1 (-2975 3000)(-3275 3000);
WIRE 16 -1 (-3275 3050)(-2975 3050);
WIRE 16 -1 (-2975 3100)(-3275 3100);
WIRE 16 -1 (-2975 3150)(-3275 3150);
WIRE 16 -1 (-2975 3200)(-3275 3200);
WIRE 16 -1 (-2975 3250)(-3275 3250);
WIRE 16 -1 (-2975 3300)(-3275 3300);
WIRE 16 -1 (-3275 3350)(-2975 3350);
WIRE 16 -1 (-3275 3400)(-2975 3400);
WIRE 16 -1 (-2975 3450)(-3275 3450);
WIRE 16 -1 (-2975 3500)(-3275 3500);
WIRE 16 -1 (-2975 3550)(-3275 3550);
WIRE 16 -1 (-2975 3600)(-3275 3600);
WIRE 16 -1 (-2975 2050)(-3275 2050);
WIRE 16 -1 (-2975 2100)(-3275 2100);
WIRE 16 -1 (-3275 2150)(-2975 2150);
WIRE 16 -1 (-3275 2200)(-2975 2200);
WIRE 16 -1 (-2975 2250)(-3275 2250);
WIRE 16 -1 (-2975 2300)(-3275 2300);
WIRE 16 -1 (-2975 2350)(-3275 2350);
WIRE 16 -1 (-2975 2400)(-3275 2400);
WIRE 16 -1 (-2975 2450)(-3275 2450);
WIRE 16 -1 (-2975 2500)(-3275 2500);
WIRE 16 -1 (-2975 2550)(-3275 2550);
FORCENOTE
BOM_COST=PROC_SOCKET
(-7925 200) 0;
DISPLAY LEFT (-7925 200);
DISPLAY 1.723404 (-7925 200);
PAINT PURPLE (-7925 200);
FORCENOTE
ROOM=CPU0
(-7925 325) 0;
DISPLAY LEFT (-7925 325);
DISPLAY 1.723404 (-7925 325);
PAINT PURPLE (-7925 325);
QUIT
